FILE_TYPE = MACRO_DRAWING;
SET COLOR_WIRE YELLOW;
SET COLOR_PROP ORANGE;
SET COLOR_DOT WHITE;
SET COLOR_ARC YELLOW;
SET COLOR_BODY GREEN;
SET COLOR_NOTE PURPLE;
SET PROP_DISPLAY VALUE;
SET PAGE_NUMBER P92;
FORCEADD UNIVERSAL_GND..1
(-2525 25);
FORCEPROP 3 LASTPIN (-2525 75) SIG_NAME GND\g
J 0
(-2515 85);
DISPLAY 0.659574 (-2515 85);
PAINT MONO (-2515 85);
DISPLAY INVISIBLE (-2515 85);
FORCEPROP 2 LAST CDS_LIB logical_power
J 0
(-2525 25);
PAINT MONO (-2525 25);
DISPLAY INVISIBLE (-2525 25);
FORCEPROP 1 LAST HDL_POWER GND
J 1
(-2500 -50);
DISPLAY 0.872340 (-2500 -50);
PAINT GREEN (-2500 -50);
DISPLAY INVISIBLE (-2500 -50);
FORCEPROP 1 LAST PATH I1
J 0
(-2450 25);
DISPLAY 0.872340 (-2450 25);
PAINT AQUA (-2450 25);
DISPLAY INVISIBLE (-2450 25);
FORCEADD OFFPAGE..1
(-3675 2150);
FORCEPROP 2 LAST $XR3 93 
J 0
(-3927 2114);
DISPLAY 0.638298 (-3927 2114);
PAINT MONO (-3927 2114);
FORCEPROP 2 LAST $XR2 91 
J 0
(-4107 2150);
DISPLAY 0.638298 (-4107 2150);
PAINT MONO (-4107 2150);
FORCEPROP 2 LAST $XR1 90 
J 0
(-4017 2150);
DISPLAY 0.638298 (-4017 2150);
PAINT MONO (-4017 2150);
FORCEPROP 2 LAST $XR0 129 
J 0
(-3927 2150);
DISPLAY 0.638298 (-3927 2150);
PAINT MONO (-3927 2150);
FORCEPROP 2 LAST CDS_LIB standard
J 0
(-3675 2150);
PAINT MONO (-3675 2150);
DISPLAY INVISIBLE (-3675 2150);
FORCEPROP 1 LAST OFFPAGE TRUE
J 0
(-3350 2025);
DISPLAY 0.872340 (-3350 2025);
DISPLAY INVISIBLE (-3350 2025);
FORCEPROP 1 LAST COMMENT_BODY TRUE
J 0
(-3550 2050);
DISPLAY 0.872340 (-3550 2050);
PAINT GREEN (-3550 2050);
DISPLAY INVISIBLE (-3550 2050);
FORCEPROP 2 LAST PATH I10
J 0
(-3625 2225);
DISPLAY 1.021277 (-3625 2225);
DISPLAY INVISIBLE (-3625 2225);
FORCEADD TAP..1
(-1100 3450);
FORCEPROP 3 LASTPIN (-1150 3450) SIG_NAME M_F_CPU0_SA_DQ<12>
J 0
(-1140 3460);
DISPLAY 0.659574 (-1140 3460);
PAINT MONO (-1140 3460);
DISPLAY INVISIBLE (-1140 3460);
FORCEPROP 1 LASTPIN (-1150 3450) BN 12
J 0
(-1162 3458);
DISPLAY 0.680851 (-1162 3458);
PAINT GREEN (-1162 3458);
FORCEPROP 2 LAST CDS_LIB standard
J 0
(-1100 3450);
PAINT MONO (-1100 3450);
DISPLAY INVISIBLE (-1100 3450);
FORCEPROP 1 LAST BODY_TYPE PLUMBING
J 0
(-1100 3500);
DISPLAY 0.872340 (-1100 3500);
PAINT GREEN (-1100 3500);
DISPLAY INVISIBLE (-1100 3500);
FORCEPROP 1 LAST HDL_TAP TRUE
J 0
(-775 3325);
DISPLAY 0.872340 (-775 3325);
DISPLAY INVISIBLE (-775 3325);
FORCEPROP 1 LAST PATH I100
J 0
(-1102 3450);
DISPLAY 0.872340 (-1102 3450);
PAINT GREEN (-1102 3450);
DISPLAY INVISIBLE (-1102 3450);
FORCEADD TAP..1
(-1100 3550);
FORCEPROP 3 LASTPIN (-1150 3550) SIG_NAME M_F_CPU0_SA_DQ<14>
J 0
(-1140 3560);
DISPLAY 0.659574 (-1140 3560);
PAINT MONO (-1140 3560);
DISPLAY INVISIBLE (-1140 3560);
FORCEPROP 1 LASTPIN (-1150 3550) BN 14
J 0
(-1162 3558);
DISPLAY 0.680851 (-1162 3558);
PAINT GREEN (-1162 3558);
FORCEPROP 2 LAST CDS_LIB standard
J 0
(-1100 3550);
PAINT MONO (-1100 3550);
DISPLAY INVISIBLE (-1100 3550);
FORCEPROP 1 LAST BODY_TYPE PLUMBING
J 0
(-1100 3600);
DISPLAY 0.872340 (-1100 3600);
PAINT GREEN (-1100 3600);
DISPLAY INVISIBLE (-1100 3600);
FORCEPROP 1 LAST HDL_TAP TRUE
J 0
(-775 3425);
DISPLAY 0.872340 (-775 3425);
DISPLAY INVISIBLE (-775 3425);
FORCEPROP 1 LAST PATH I101
J 0
(-1102 3550);
DISPLAY 0.872340 (-1102 3550);
PAINT GREEN (-1102 3550);
DISPLAY INVISIBLE (-1102 3550);
FORCEADD TAP..1
(-1100 3500);
FORCEPROP 3 LASTPIN (-1150 3500) SIG_NAME M_F_CPU0_SA_DQ<13>
J 0
(-1140 3510);
DISPLAY 0.659574 (-1140 3510);
PAINT MONO (-1140 3510);
DISPLAY INVISIBLE (-1140 3510);
FORCEPROP 1 LASTPIN (-1150 3500) BN 13
J 0
(-1162 3508);
DISPLAY 0.680851 (-1162 3508);
PAINT GREEN (-1162 3508);
FORCEPROP 2 LAST CDS_LIB standard
J 0
(-1100 3500);
PAINT MONO (-1100 3500);
DISPLAY INVISIBLE (-1100 3500);
FORCEPROP 1 LAST BODY_TYPE PLUMBING
J 0
(-1100 3550);
DISPLAY 0.872340 (-1100 3550);
PAINT GREEN (-1100 3550);
DISPLAY INVISIBLE (-1100 3550);
FORCEPROP 1 LAST HDL_TAP TRUE
J 0
(-775 3375);
DISPLAY 0.872340 (-775 3375);
DISPLAY INVISIBLE (-775 3375);
FORCEPROP 1 LAST PATH I102
J 0
(-1102 3500);
DISPLAY 0.872340 (-1102 3500);
PAINT GREEN (-1102 3500);
DISPLAY INVISIBLE (-1102 3500);
FORCEADD TAP..1
(-1100 3700);
FORCEPROP 3 LASTPIN (-1150 3700) SIG_NAME M_F_CPU0_SA_DQ<17>
J 0
(-1140 3710);
DISPLAY 0.659574 (-1140 3710);
PAINT MONO (-1140 3710);
DISPLAY INVISIBLE (-1140 3710);
FORCEPROP 1 LASTPIN (-1150 3700) BN 17
J 0
(-1162 3708);
DISPLAY 0.680851 (-1162 3708);
PAINT GREEN (-1162 3708);
FORCEPROP 2 LAST CDS_LIB standard
J 0
(-1100 3700);
PAINT MONO (-1100 3700);
DISPLAY INVISIBLE (-1100 3700);
FORCEPROP 1 LAST BODY_TYPE PLUMBING
J 0
(-1100 3750);
DISPLAY 0.872340 (-1100 3750);
PAINT GREEN (-1100 3750);
DISPLAY INVISIBLE (-1100 3750);
FORCEPROP 1 LAST HDL_TAP TRUE
J 0
(-775 3575);
DISPLAY 0.872340 (-775 3575);
DISPLAY INVISIBLE (-775 3575);
FORCEPROP 1 LAST PATH I103
J 0
(-1102 3700);
DISPLAY 0.872340 (-1102 3700);
PAINT GREEN (-1102 3700);
DISPLAY INVISIBLE (-1102 3700);
FORCEADD TAP..1
(-1100 3600);
FORCEPROP 3 LASTPIN (-1150 3600) SIG_NAME M_F_CPU0_SA_DQ<15>
J 0
(-1140 3610);
DISPLAY 0.659574 (-1140 3610);
PAINT MONO (-1140 3610);
DISPLAY INVISIBLE (-1140 3610);
FORCEPROP 1 LASTPIN (-1150 3600) BN 15
J 0
(-1162 3608);
DISPLAY 0.680851 (-1162 3608);
PAINT GREEN (-1162 3608);
FORCEPROP 2 LAST CDS_LIB standard
J 0
(-1100 3600);
PAINT MONO (-1100 3600);
DISPLAY INVISIBLE (-1100 3600);
FORCEPROP 1 LAST BODY_TYPE PLUMBING
J 0
(-1100 3650);
DISPLAY 0.872340 (-1100 3650);
PAINT GREEN (-1100 3650);
DISPLAY INVISIBLE (-1100 3650);
FORCEPROP 1 LAST HDL_TAP TRUE
J 0
(-775 3475);
DISPLAY 0.872340 (-775 3475);
DISPLAY INVISIBLE (-775 3475);
FORCEPROP 1 LAST PATH I104
J 0
(-1102 3600);
DISPLAY 0.872340 (-1102 3600);
PAINT GREEN (-1102 3600);
DISPLAY INVISIBLE (-1102 3600);
FORCEADD TAP..1
(-1100 3650);
FORCEPROP 3 LASTPIN (-1150 3650) SIG_NAME M_F_CPU0_SA_DQ<16>
J 0
(-1140 3660);
DISPLAY 0.659574 (-1140 3660);
PAINT MONO (-1140 3660);
DISPLAY INVISIBLE (-1140 3660);
FORCEPROP 1 LASTPIN (-1150 3650) BN 16
J 0
(-1162 3658);
DISPLAY 0.680851 (-1162 3658);
PAINT GREEN (-1162 3658);
FORCEPROP 2 LAST CDS_LIB standard
J 0
(-1100 3650);
PAINT MONO (-1100 3650);
DISPLAY INVISIBLE (-1100 3650);
FORCEPROP 1 LAST BODY_TYPE PLUMBING
J 0
(-1100 3700);
DISPLAY 0.872340 (-1100 3700);
PAINT GREEN (-1100 3700);
DISPLAY INVISIBLE (-1100 3700);
FORCEPROP 1 LAST HDL_TAP TRUE
J 0
(-775 3525);
DISPLAY 0.872340 (-775 3525);
DISPLAY INVISIBLE (-775 3525);
FORCEPROP 1 LAST PATH I105
J 0
(-1102 3650);
DISPLAY 0.872340 (-1102 3650);
PAINT GREEN (-1102 3650);
DISPLAY INVISIBLE (-1102 3650);
FORCEADD TAP..1
(-1100 3800);
FORCEPROP 3 LASTPIN (-1150 3800) SIG_NAME M_F_CPU0_SA_DQ<19>
J 0
(-1140 3810);
DISPLAY 0.659574 (-1140 3810);
PAINT MONO (-1140 3810);
DISPLAY INVISIBLE (-1140 3810);
FORCEPROP 1 LASTPIN (-1150 3800) BN 19
J 0
(-1162 3808);
DISPLAY 0.680851 (-1162 3808);
PAINT GREEN (-1162 3808);
FORCEPROP 2 LAST CDS_LIB standard
J 0
(-1100 3800);
PAINT MONO (-1100 3800);
DISPLAY INVISIBLE (-1100 3800);
FORCEPROP 1 LAST BODY_TYPE PLUMBING
J 0
(-1100 3850);
DISPLAY 0.872340 (-1100 3850);
PAINT GREEN (-1100 3850);
DISPLAY INVISIBLE (-1100 3850);
FORCEPROP 1 LAST HDL_TAP TRUE
J 0
(-775 3675);
DISPLAY 0.872340 (-775 3675);
DISPLAY INVISIBLE (-775 3675);
FORCEPROP 1 LAST PATH I106
J 0
(-1102 3800);
DISPLAY 0.872340 (-1102 3800);
PAINT GREEN (-1102 3800);
DISPLAY INVISIBLE (-1102 3800);
FORCEADD TAP..1
(-1100 3750);
FORCEPROP 3 LASTPIN (-1150 3750) SIG_NAME M_F_CPU0_SA_DQ<18>
J 0
(-1140 3760);
DISPLAY 0.659574 (-1140 3760);
PAINT MONO (-1140 3760);
DISPLAY INVISIBLE (-1140 3760);
FORCEPROP 1 LASTPIN (-1150 3750) BN 18
J 0
(-1162 3758);
DISPLAY 0.680851 (-1162 3758);
PAINT GREEN (-1162 3758);
FORCEPROP 2 LAST CDS_LIB standard
J 0
(-1100 3750);
PAINT MONO (-1100 3750);
DISPLAY INVISIBLE (-1100 3750);
FORCEPROP 1 LAST BODY_TYPE PLUMBING
J 0
(-1100 3800);
DISPLAY 0.872340 (-1100 3800);
PAINT GREEN (-1100 3800);
DISPLAY INVISIBLE (-1100 3800);
FORCEPROP 1 LAST HDL_TAP TRUE
J 0
(-775 3625);
DISPLAY 0.872340 (-775 3625);
DISPLAY INVISIBLE (-775 3625);
FORCEPROP 1 LAST PATH I107
J 0
(-1102 3750);
DISPLAY 0.872340 (-1102 3750);
PAINT GREEN (-1102 3750);
DISPLAY INVISIBLE (-1102 3750);
FORCEADD TAP..1
(-1100 3950);
FORCEPROP 3 LASTPIN (-1150 3950) SIG_NAME M_F_CPU0_SA_DQ<22>
J 0
(-1140 3960);
DISPLAY 0.659574 (-1140 3960);
PAINT MONO (-1140 3960);
DISPLAY INVISIBLE (-1140 3960);
FORCEPROP 1 LASTPIN (-1150 3950) BN 22
J 0
(-1162 3958);
DISPLAY 0.680851 (-1162 3958);
PAINT GREEN (-1162 3958);
FORCEPROP 2 LAST CDS_LIB standard
J 0
(-1100 3950);
DISPLAY INVISIBLE (-1100 3950);
FORCEPROP 1 LAST BODY_TYPE PLUMBING
J 0
(-1100 4000);
DISPLAY 0.872340 (-1100 4000);
PAINT GREEN (-1100 4000);
DISPLAY INVISIBLE (-1100 4000);
FORCEPROP 1 LAST HDL_TAP TRUE
J 0
(-775 3825);
DISPLAY 0.872340 (-775 3825);
DISPLAY INVISIBLE (-775 3825);
FORCEPROP 1 LAST PATH I108
J 0
(-1102 3950);
DISPLAY 0.872340 (-1102 3950);
PAINT GREEN (-1102 3950);
DISPLAY INVISIBLE (-1102 3950);
FORCEADD TAP..1
(-1100 3900);
FORCEPROP 3 LASTPIN (-1150 3900) SIG_NAME M_F_CPU0_SA_DQ<21>
J 0
(-1140 3910);
DISPLAY 0.659574 (-1140 3910);
PAINT MONO (-1140 3910);
DISPLAY INVISIBLE (-1140 3910);
FORCEPROP 1 LASTPIN (-1150 3900) BN 21
J 0
(-1162 3908);
DISPLAY 0.680851 (-1162 3908);
PAINT GREEN (-1162 3908);
FORCEPROP 2 LAST CDS_LIB standard
J 0
(-1100 3900);
PAINT MONO (-1100 3900);
DISPLAY INVISIBLE (-1100 3900);
FORCEPROP 1 LAST BODY_TYPE PLUMBING
J 0
(-1100 3950);
DISPLAY 0.872340 (-1100 3950);
PAINT GREEN (-1100 3950);
DISPLAY INVISIBLE (-1100 3950);
FORCEPROP 1 LAST HDL_TAP TRUE
J 0
(-775 3775);
DISPLAY 0.872340 (-775 3775);
DISPLAY INVISIBLE (-775 3775);
FORCEPROP 1 LAST PATH I109
J 0
(-1102 3900);
DISPLAY 0.872340 (-1102 3900);
PAINT GREEN (-1102 3900);
DISPLAY INVISIBLE (-1102 3900);
FORCEADD OFFPAGE..1
(-3675 2050);
FORCEPROP 2 LAST $XR1 93 
J 0
(-3986 2050);
DISPLAY 0.638298 (-3986 2050);
PAINT MONO (-3986 2050);
FORCEPROP 2 LAST $XR0 25 
J 0
(-3896 2050);
DISPLAY 0.638298 (-3896 2050);
PAINT MONO (-3896 2050);
FORCEPROP 2 LAST CDS_LIB standard
J 0
(-3675 2050);
PAINT MONO (-3675 2050);
DISPLAY INVISIBLE (-3675 2050);
FORCEPROP 1 LAST OFFPAGE TRUE
J 0
(-3350 1925);
DISPLAY 0.872340 (-3350 1925);
DISPLAY INVISIBLE (-3350 1925);
FORCEPROP 1 LAST COMMENT_BODY TRUE
J 0
(-3550 1950);
DISPLAY 0.872340 (-3550 1950);
PAINT GREEN (-3550 1950);
DISPLAY INVISIBLE (-3550 1950);
FORCEPROP 2 LAST PATH I11
J 0
(-3625 2125);
DISPLAY 1.021277 (-3625 2125);
DISPLAY INVISIBLE (-3625 2125);
FORCEADD TAP..1
(-1100 3850);
FORCEPROP 3 LASTPIN (-1150 3850) SIG_NAME M_F_CPU0_SA_DQ<20>
J 0
(-1140 3860);
DISPLAY 0.659574 (-1140 3860);
PAINT MONO (-1140 3860);
DISPLAY INVISIBLE (-1140 3860);
FORCEPROP 1 LASTPIN (-1150 3850) BN 20
J 0
(-1162 3858);
DISPLAY 0.680851 (-1162 3858);
PAINT GREEN (-1162 3858);
FORCEPROP 2 LAST CDS_LIB standard
J 0
(-1100 3850);
PAINT MONO (-1100 3850);
DISPLAY INVISIBLE (-1100 3850);
FORCEPROP 1 LAST BODY_TYPE PLUMBING
J 0
(-1100 3900);
DISPLAY 0.872340 (-1100 3900);
PAINT GREEN (-1100 3900);
DISPLAY INVISIBLE (-1100 3900);
FORCEPROP 1 LAST HDL_TAP TRUE
J 0
(-775 3725);
DISPLAY 0.872340 (-775 3725);
DISPLAY INVISIBLE (-775 3725);
FORCEPROP 1 LAST PATH I110
J 0
(-1102 3850);
DISPLAY 0.872340 (-1102 3850);
PAINT GREEN (-1102 3850);
DISPLAY INVISIBLE (-1102 3850);
FORCEADD TAP..1
(-1100 4050);
FORCEPROP 3 LASTPIN (-1150 4050) SIG_NAME M_F_CPU0_SA_DQ<24>
J 0
(-1140 4060);
DISPLAY 0.659574 (-1140 4060);
PAINT MONO (-1140 4060);
DISPLAY INVISIBLE (-1140 4060);
FORCEPROP 1 LASTPIN (-1150 4050) BN 24
J 0
(-1162 4058);
DISPLAY 0.680851 (-1162 4058);
PAINT GREEN (-1162 4058);
FORCEPROP 2 LAST CDS_LIB standard
J 0
(-1100 4050);
DISPLAY INVISIBLE (-1100 4050);
FORCEPROP 1 LAST BODY_TYPE PLUMBING
J 0
(-1100 4100);
DISPLAY 0.872340 (-1100 4100);
PAINT GREEN (-1100 4100);
DISPLAY INVISIBLE (-1100 4100);
FORCEPROP 1 LAST HDL_TAP TRUE
J 0
(-775 3925);
DISPLAY 0.872340 (-775 3925);
DISPLAY INVISIBLE (-775 3925);
FORCEPROP 1 LAST PATH I111
J 0
(-1102 4050);
DISPLAY 0.872340 (-1102 4050);
PAINT GREEN (-1102 4050);
DISPLAY INVISIBLE (-1102 4050);
FORCEADD TAP..1
(-1100 4000);
FORCEPROP 3 LASTPIN (-1150 4000) SIG_NAME M_F_CPU0_SA_DQ<23>
J 0
(-1140 4010);
DISPLAY 0.659574 (-1140 4010);
PAINT MONO (-1140 4010);
DISPLAY INVISIBLE (-1140 4010);
FORCEPROP 1 LASTPIN (-1150 4000) BN 23
J 0
(-1162 4008);
DISPLAY 0.680851 (-1162 4008);
PAINT GREEN (-1162 4008);
FORCEPROP 2 LAST CDS_LIB standard
J 0
(-1100 4000);
DISPLAY INVISIBLE (-1100 4000);
FORCEPROP 1 LAST BODY_TYPE PLUMBING
J 0
(-1100 4050);
DISPLAY 0.872340 (-1100 4050);
PAINT GREEN (-1100 4050);
DISPLAY INVISIBLE (-1100 4050);
FORCEPROP 1 LAST HDL_TAP TRUE
J 0
(-775 3875);
DISPLAY 0.872340 (-775 3875);
DISPLAY INVISIBLE (-775 3875);
FORCEPROP 1 LAST PATH I112
J 0
(-1102 4000);
DISPLAY 0.872340 (-1102 4000);
PAINT GREEN (-1102 4000);
DISPLAY INVISIBLE (-1102 4000);
FORCEADD TAP..1
(-1100 4200);
FORCEPROP 3 LASTPIN (-1150 4200) SIG_NAME M_F_CPU0_SA_DQ<27>
J 0
(-1140 4210);
DISPLAY 0.659574 (-1140 4210);
PAINT MONO (-1140 4210);
DISPLAY INVISIBLE (-1140 4210);
FORCEPROP 1 LASTPIN (-1150 4200) BN 27
J 0
(-1162 4208);
DISPLAY 0.680851 (-1162 4208);
PAINT GREEN (-1162 4208);
FORCEPROP 2 LAST CDS_LIB standard
J 0
(-1100 4200);
DISPLAY INVISIBLE (-1100 4200);
FORCEPROP 1 LAST BODY_TYPE PLUMBING
J 0
(-1100 4250);
DISPLAY 0.872340 (-1100 4250);
PAINT GREEN (-1100 4250);
DISPLAY INVISIBLE (-1100 4250);
FORCEPROP 1 LAST HDL_TAP TRUE
J 0
(-775 4075);
DISPLAY 0.872340 (-775 4075);
DISPLAY INVISIBLE (-775 4075);
FORCEPROP 1 LAST PATH I113
J 0
(-1102 4200);
DISPLAY 0.872340 (-1102 4200);
PAINT GREEN (-1102 4200);
DISPLAY INVISIBLE (-1102 4200);
FORCEADD TAP..1
(-1100 4150);
FORCEPROP 3 LASTPIN (-1150 4150) SIG_NAME M_F_CPU0_SA_DQ<26>
J 0
(-1140 4160);
DISPLAY 0.659574 (-1140 4160);
PAINT MONO (-1140 4160);
DISPLAY INVISIBLE (-1140 4160);
FORCEPROP 1 LASTPIN (-1150 4150) BN 26
J 0
(-1162 4158);
DISPLAY 0.680851 (-1162 4158);
PAINT GREEN (-1162 4158);
FORCEPROP 2 LAST CDS_LIB standard
J 0
(-1100 4150);
DISPLAY INVISIBLE (-1100 4150);
FORCEPROP 1 LAST BODY_TYPE PLUMBING
J 0
(-1100 4200);
DISPLAY 0.872340 (-1100 4200);
PAINT GREEN (-1100 4200);
DISPLAY INVISIBLE (-1100 4200);
FORCEPROP 1 LAST HDL_TAP TRUE
J 0
(-775 4025);
DISPLAY 0.872340 (-775 4025);
DISPLAY INVISIBLE (-775 4025);
FORCEPROP 1 LAST PATH I114
J 0
(-1102 4150);
DISPLAY 0.872340 (-1102 4150);
PAINT GREEN (-1102 4150);
DISPLAY INVISIBLE (-1102 4150);
FORCEADD TAP..1
(-1100 4100);
FORCEPROP 3 LASTPIN (-1150 4100) SIG_NAME M_F_CPU0_SA_DQ<25>
J 0
(-1140 4110);
DISPLAY 0.659574 (-1140 4110);
PAINT MONO (-1140 4110);
DISPLAY INVISIBLE (-1140 4110);
FORCEPROP 1 LASTPIN (-1150 4100) BN 25
J 0
(-1162 4108);
DISPLAY 0.680851 (-1162 4108);
PAINT GREEN (-1162 4108);
FORCEPROP 2 LAST CDS_LIB standard
J 0
(-1100 4100);
DISPLAY INVISIBLE (-1100 4100);
FORCEPROP 1 LAST BODY_TYPE PLUMBING
J 0
(-1100 4150);
DISPLAY 0.872340 (-1100 4150);
PAINT GREEN (-1100 4150);
DISPLAY INVISIBLE (-1100 4150);
FORCEPROP 1 LAST HDL_TAP TRUE
J 0
(-775 3975);
DISPLAY 0.872340 (-775 3975);
DISPLAY INVISIBLE (-775 3975);
FORCEPROP 1 LAST PATH I115
J 0
(-1102 4100);
DISPLAY 0.872340 (-1102 4100);
PAINT GREEN (-1102 4100);
DISPLAY INVISIBLE (-1102 4100);
FORCEADD TAP..1
(-1100 4300);
FORCEPROP 3 LASTPIN (-1150 4300) SIG_NAME M_F_CPU0_SA_DQ<29>
J 0
(-1140 4310);
DISPLAY 0.659574 (-1140 4310);
PAINT MONO (-1140 4310);
DISPLAY INVISIBLE (-1140 4310);
FORCEPROP 1 LASTPIN (-1150 4300) BN 29
J 0
(-1162 4308);
DISPLAY 0.680851 (-1162 4308);
PAINT GREEN (-1162 4308);
FORCEPROP 2 LAST CDS_LIB standard
J 0
(-1100 4300);
DISPLAY INVISIBLE (-1100 4300);
FORCEPROP 1 LAST BODY_TYPE PLUMBING
J 0
(-1100 4350);
DISPLAY 0.872340 (-1100 4350);
PAINT GREEN (-1100 4350);
DISPLAY INVISIBLE (-1100 4350);
FORCEPROP 1 LAST HDL_TAP TRUE
J 0
(-775 4175);
DISPLAY 0.872340 (-775 4175);
DISPLAY INVISIBLE (-775 4175);
FORCEPROP 1 LAST PATH I116
J 0
(-1102 4300);
DISPLAY 0.872340 (-1102 4300);
PAINT GREEN (-1102 4300);
DISPLAY INVISIBLE (-1102 4300);
FORCEADD TAP..1
(-1100 4250);
FORCEPROP 3 LASTPIN (-1150 4250) SIG_NAME M_F_CPU0_SA_DQ<28>
J 0
(-1140 4260);
DISPLAY 0.659574 (-1140 4260);
PAINT MONO (-1140 4260);
DISPLAY INVISIBLE (-1140 4260);
FORCEPROP 1 LASTPIN (-1150 4250) BN 28
J 0
(-1162 4258);
DISPLAY 0.680851 (-1162 4258);
PAINT GREEN (-1162 4258);
FORCEPROP 2 LAST CDS_LIB standard
J 0
(-1100 4250);
DISPLAY INVISIBLE (-1100 4250);
FORCEPROP 1 LAST BODY_TYPE PLUMBING
J 0
(-1100 4300);
DISPLAY 0.872340 (-1100 4300);
PAINT GREEN (-1100 4300);
DISPLAY INVISIBLE (-1100 4300);
FORCEPROP 1 LAST HDL_TAP TRUE
J 0
(-775 4125);
DISPLAY 0.872340 (-775 4125);
DISPLAY INVISIBLE (-775 4125);
FORCEPROP 1 LAST PATH I117
J 0
(-1102 4250);
DISPLAY 0.872340 (-1102 4250);
PAINT GREEN (-1102 4250);
DISPLAY INVISIBLE (-1102 4250);
FORCEADD TAP..1
(-1100 4350);
FORCEPROP 3 LASTPIN (-1150 4350) SIG_NAME M_F_CPU0_SA_DQ<30>
J 0
(-1140 4360);
DISPLAY 0.659574 (-1140 4360);
PAINT MONO (-1140 4360);
DISPLAY INVISIBLE (-1140 4360);
FORCEPROP 1 LASTPIN (-1150 4350) BN 30
J 0
(-1162 4358);
DISPLAY 0.680851 (-1162 4358);
PAINT GREEN (-1162 4358);
FORCEPROP 2 LAST CDS_LIB standard
J 0
(-1100 4350);
DISPLAY INVISIBLE (-1100 4350);
FORCEPROP 1 LAST BODY_TYPE PLUMBING
J 0
(-1100 4400);
DISPLAY 0.872340 (-1100 4400);
PAINT GREEN (-1100 4400);
DISPLAY INVISIBLE (-1100 4400);
FORCEPROP 1 LAST HDL_TAP TRUE
J 0
(-775 4225);
DISPLAY 0.872340 (-775 4225);
DISPLAY INVISIBLE (-775 4225);
FORCEPROP 1 LAST PATH I118
J 0
(-1102 4350);
DISPLAY 0.872340 (-1102 4350);
PAINT GREEN (-1102 4350);
DISPLAY INVISIBLE (-1102 4350);
FORCEADD TAP..1
(-1100 4400);
FORCEPROP 3 LASTPIN (-1150 4400) SIG_NAME M_F_CPU0_SA_DQ<31>
J 0
(-1140 4410);
DISPLAY 0.659574 (-1140 4410);
PAINT MONO (-1140 4410);
DISPLAY INVISIBLE (-1140 4410);
FORCEPROP 1 LASTPIN (-1150 4400) BN 31
J 0
(-1162 4408);
DISPLAY 0.680851 (-1162 4408);
PAINT GREEN (-1162 4408);
FORCEPROP 2 LAST CDS_LIB standard
J 0
(-1100 4400);
DISPLAY INVISIBLE (-1100 4400);
FORCEPROP 1 LAST BODY_TYPE PLUMBING
J 0
(-1100 4450);
DISPLAY 0.872340 (-1100 4450);
PAINT GREEN (-1100 4450);
DISPLAY INVISIBLE (-1100 4450);
FORCEPROP 1 LAST HDL_TAP TRUE
J 0
(-775 4275);
DISPLAY 0.872340 (-775 4275);
DISPLAY INVISIBLE (-775 4275);
FORCEPROP 1 LAST PATH I119
J 0
(-1102 4400);
DISPLAY 0.872340 (-1102 4400);
PAINT GREEN (-1102 4400);
DISPLAY INVISIBLE (-1102 4400);
FORCEADD VCC_CORE..1
(-3575 2275);
FORCEPROP 3 LASTPIN (-3575 2225) SIG_NAME P3V3_AUX\g
J 0
(-3565 2235);
DISPLAY 0.659574 (-3565 2235);
PAINT MONO (-3565 2235);
DISPLAY INVISIBLE (-3565 2235);
FORCEPROP 1 LAST HDL_POWER P3V3_AUX
J 1
(-3575 2325);
DISPLAY 1.148936 (-3575 2325);
PAINT GREEN (-3575 2325);
FORCEPROP 2 LAST CDS_LIB logical_power
J 0
(-3575 2275);
PAINT MONO (-3575 2275);
DISPLAY INVISIBLE (-3575 2275);
FORCEPROP 1 LAST PATH I12
J 0
(-3525 2300);
DISPLAY 0.872340 (-3525 2300);
PAINT AQUA (-3525 2300);
DISPLAY INVISIBLE (-3525 2300);
FORCEADD UNIVERSAL_GND..1
(625 150);
FORCEPROP 3 LASTPIN (625 200) SIG_NAME GND\g
J 0
(635 210);
DISPLAY 0.659574 (635 210);
PAINT MONO (635 210);
DISPLAY INVISIBLE (635 210);
FORCEPROP 2 LAST CDS_LIB logical_power
J 0
(625 150);
PAINT MONO (625 150);
DISPLAY INVISIBLE (625 150);
FORCEPROP 1 LAST HDL_POWER GND
J 1
(650 75);
DISPLAY 0.872340 (650 75);
PAINT GREEN (650 75);
DISPLAY INVISIBLE (650 75);
FORCEPROP 1 LAST PATH I120
J 0
(700 150);
DISPLAY 0.872340 (700 150);
PAINT AQUA (700 150);
DISPLAY INVISIBLE (700 150);
FORCEADD UNIVERSAL_GND..1
(2250 150);
FORCEPROP 3 LASTPIN (2250 200) SIG_NAME GND\g
J 0
(2260 210);
DISPLAY 0.659574 (2260 210);
PAINT MONO (2260 210);
DISPLAY INVISIBLE (2260 210);
FORCEPROP 2 LAST CDS_LIB logical_power
J 0
(2250 150);
PAINT MONO (2250 150);
DISPLAY INVISIBLE (2250 150);
FORCEPROP 1 LAST HDL_POWER GND
J 1
(2275 75);
DISPLAY 0.872340 (2275 75);
PAINT GREEN (2275 75);
DISPLAY INVISIBLE (2275 75);
FORCEPROP 1 LAST PATH I121
J 0
(2325 150);
DISPLAY 0.872340 (2325 150);
PAINT AQUA (2325 150);
DISPLAY INVISIBLE (2325 150);
FORCEADD Q_CAP..1
(625 525);
FORCEPROP 1 LAST PART_NUMBER CH5221MEB00
J 0
(675 375);
DISPLAY 0.978723 (675 375);
DISPLAY INVISIBLE (675 375);
FORCEPROP 1 LAST PACK_TYPE C0402
J 0
(675 325);
DISPLAY 0.978723 (675 325);
FORCEPROP 1 LAST MATERIAL X6S
J 0
(675 425);
DISPLAY 0.978723 (675 425);
FORCEPROP 1 LAST TOLERANCE 20%
J 0
(675 475);
DISPLAY 0.978723 (675 475);
FORCEPROP 1 LAST VALUE 2.2UF
J 0
(675 575);
DISPLAY 0.978723 (675 575);
FORCEPROP 1 LAST VOLTAGE 6.3V
J 0
(675 525);
DISPLAY 0.978723 (675 525);
FORCEPROP 1 LAST $LOCATION C32
J 0
(675 625);
DISPLAY 0.978723 (675 625);
FORCEPROP 1 LASTPIN (625 625) $PN 1
J 0
(635 605);
DISPLAY 0.787234 (635 605);
FORCEPROP 1 LASTPIN (625 425) $PN 2
J 0
(635 405);
DISPLAY 0.787234 (635 405);
FORCEPROP 2 LAST CDS_LIB pure_quanta
J 0
(625 525);
PAINT MONO (625 525);
DISPLAY INVISIBLE (625 525);
FORCEPROP 2 LAST CDS_LOCATION C32
J 0
(675 725);
DISPLAY 1.021277 (675 725);
DISPLAY INVISIBLE (675 725);
FORCEPROP 2 LAST $SEC 1
J 0
(675 725);
DISPLAY 0.680851 (675 725);
PAINT MONO (675 725);
DISPLAY INVISIBLE (675 725);
FORCEPROP 2 LAST CDS_SEC 1
J 0
(675 725);
DISPLAY 1.021277 (675 725);
DISPLAY INVISIBLE (675 725);
FORCEPROP 1 LAST PATH I122
J 0
(675 675);
DISPLAY 0.978723 (675 675);
PAINT WHITE (675 675);
DISPLAY INVISIBLE (675 675);
FORCEADD VCC_CORE..1
(625 850);
FORCEPROP 3 LASTPIN (625 800) SIG_NAME P3V3_AUX\g
J 0
(635 810);
DISPLAY 0.659574 (635 810);
PAINT MONO (635 810);
DISPLAY INVISIBLE (635 810);
FORCEPROP 1 LAST HDL_POWER P3V3_AUX
J 1
(625 900);
DISPLAY 1.148936 (625 900);
PAINT GREEN (625 900);
FORCEPROP 2 LAST CDS_LIB logical_power
J 0
(625 850);
PAINT MONO (625 850);
DISPLAY INVISIBLE (625 850);
FORCEPROP 1 LAST PATH I123
J 0
(675 875);
DISPLAY 0.872340 (675 875);
PAINT AQUA (675 875);
DISPLAY INVISIBLE (675 875);
FORCEADD OFFPAGE..3
(-275 2775);
FORCEPROP 2 LAST $XR1 93 
J 0
(29 2775);
DISPLAY 0.638298 (29 2775);
PAINT MONO (29 2775);
FORCEPROP 2 LAST $XR0 25 
J 0
(-61 2775);
DISPLAY 0.638298 (-61 2775);
PAINT MONO (-61 2775);
FORCEPROP 2 LAST CDS_LIB standard
J 2
(-275 2775);
DISPLAY INVISIBLE (-275 2775);
FORCEPROP 1 LAST OFFPAGE TRUE
J 0
(50 2650);
DISPLAY 0.872340 (50 2650);
DISPLAY INVISIBLE (50 2650);
FORCEPROP 1 LAST COMMENT_BODY TRUE
J 0
(-325 2675);
DISPLAY 0.872340 (-325 2675);
PAINT GREEN (-325 2675);
DISPLAY INVISIBLE (-325 2675);
FORCEPROP 2 LAST PATH I124
J 0
(-75 2850);
DISPLAY 1.021277 (-75 2850);
DISPLAY INVISIBLE (-75 2850);
FORCEADD OFFPAGE..3
(-275 4425);
FORCEPROP 2 LAST $XR1 93 
J 0
(29 4425);
DISPLAY 0.638298 (29 4425);
PAINT MONO (29 4425);
FORCEPROP 2 LAST $XR0 25 
J 0
(-61 4425);
DISPLAY 0.638298 (-61 4425);
PAINT MONO (-61 4425);
FORCEPROP 2 LAST CDS_LIB standard
J 2
(-275 4425);
DISPLAY INVISIBLE (-275 4425);
FORCEPROP 1 LAST OFFPAGE TRUE
J 0
(50 4300);
DISPLAY 0.872340 (50 4300);
DISPLAY INVISIBLE (50 4300);
FORCEPROP 1 LAST COMMENT_BODY TRUE
J 0
(-325 4325);
DISPLAY 0.872340 (-325 4325);
PAINT GREEN (-325 4325);
DISPLAY INVISIBLE (-325 4325);
FORCEPROP 2 LAST PATH I125
J 0
(-75 4500);
DISPLAY 1.021277 (-75 4500);
DISPLAY INVISIBLE (-75 4500);
FORCEADD Q_CAP..1
(1625 525);
FORCEPROP 1 LAST PART_NUMBER CH6103KEA00
J 0
(1675 375);
DISPLAY 0.978723 (1675 375);
DISPLAY INVISIBLE (1675 375);
FORCEPROP 1 LAST PACK_TYPE C0805
J 0
(1675 325);
DISPLAY 0.978723 (1675 325);
FORCEPROP 1 LAST TOLERANCE 10%
J 0
(1675 475);
DISPLAY 0.978723 (1675 475);
FORCEPROP 1 LAST VALUE 10UF
J 0
(1675 575);
DISPLAY 0.978723 (1675 575);
FORCEPROP 1 LAST VOLTAGE 16V
J 0
(1675 525);
DISPLAY 0.978723 (1675 525);
FORCEPROP 1 LAST MATERIAL X6S
J 0
(1675 425);
DISPLAY 0.978723 (1675 425);
FORCEPROP 1 LAST $LOCATION C33
J 0
(1675 625);
DISPLAY 0.978723 (1675 625);
FORCEPROP 1 LASTPIN (1625 625) $PN 1
J 0
(1635 605);
DISPLAY 0.787234 (1635 605);
FORCEPROP 1 LASTPIN (1625 425) $PN 2
J 0
(1635 405);
DISPLAY 0.787234 (1635 405);
FORCEPROP 2 LAST CDS_LIB pure_quanta
J 0
(1625 525);
PAINT MONO (1625 525);
DISPLAY INVISIBLE (1625 525);
FORCEPROP 2 LAST CDS_LOCATION C33
J 0
(1675 725);
DISPLAY 1.021277 (1675 725);
DISPLAY INVISIBLE (1675 725);
FORCEPROP 2 LAST $SEC 1
J 0
(1675 725);
DISPLAY 0.680851 (1675 725);
PAINT MONO (1675 725);
DISPLAY INVISIBLE (1675 725);
FORCEPROP 2 LAST CDS_SEC 1
J 0
(1675 725);
DISPLAY 1.021277 (1675 725);
DISPLAY INVISIBLE (1675 725);
FORCEPROP 1 LAST PATH I127
J 0
(1675 675);
DISPLAY 0.978723 (1675 675);
PAINT WHITE (1675 675);
DISPLAY INVISIBLE (1675 675);
FORCEADD VCC_CORE..1
(1625 850);
FORCEPROP 3 LASTPIN (1625 800) SIG_NAME P12V_S3_AUX_CPU0_NVDIMM\g
J 0
(1635 810);
DISPLAY 0.659574 (1635 810);
PAINT MONO (1635 810);
DISPLAY INVISIBLE (1635 810);
FORCEPROP 1 LAST HDL_POWER P12V_S3_AUX_CPU0_NVDIMM
J 1
(1625 900);
DISPLAY 1.148936 (1625 900);
PAINT GREEN (1625 900);
FORCEPROP 2 LAST CDS_LIB logical_power
J 0
(1625 850);
PAINT MONO (1625 850);
DISPLAY INVISIBLE (1625 850);
FORCEPROP 1 LAST PATH I128
J 0
(1675 875);
DISPLAY 0.872340 (1675 875);
PAINT AQUA (1675 875);
DISPLAY INVISIBLE (1675 875);
FORCEADD TAP..1
(1825 2400);
FORCEPROP 3 LASTPIN (1775 2400) SIG_NAME M_F_CPU0_SB_DQS_DN<0>
J 0
(1785 2410);
DISPLAY 0.659574 (1785 2410);
PAINT MONO (1785 2410);
DISPLAY INVISIBLE (1785 2410);
FORCEPROP 1 LASTPIN (1775 2400) BN 0
J 0
(1763 2408);
DISPLAY 0.680851 (1763 2408);
PAINT GREEN (1763 2408);
FORCEPROP 2 LAST CDS_LIB standard
J 0
(1825 2400);
PAINT MONO (1825 2400);
DISPLAY INVISIBLE (1825 2400);
FORCEPROP 1 LAST BODY_TYPE PLUMBING
J 0
(1825 2450);
DISPLAY 0.872340 (1825 2450);
PAINT GREEN (1825 2450);
DISPLAY INVISIBLE (1825 2450);
FORCEPROP 1 LAST HDL_TAP TRUE
J 0
(2150 2275);
DISPLAY 0.872340 (2150 2275);
DISPLAY INVISIBLE (2150 2275);
FORCEPROP 1 LAST PATH I129
J 0
(1823 2400);
DISPLAY 0.872340 (1823 2400);
PAINT GREEN (1823 2400);
DISPLAY INVISIBLE (1823 2400);
FORCEADD OFFPAGE..3
R 2
(-3675 2575);
FORCEPROP 2 LAST $XR1 93 
J 0
(-4014 2575);
DISPLAY 0.638298 (-4014 2575);
PAINT MONO (-4014 2575);
FORCEPROP 2 LAST $XR0 25 
J 0
(-3924 2575);
DISPLAY 0.638298 (-3924 2575);
PAINT MONO (-3924 2575);
FORCEPROP 2 LAST CDS_LIB standard
J 0
(-3675 2575);
PAINT MONO (-3675 2575);
DISPLAY INVISIBLE (-3675 2575);
FORCEPROP 1 LAST OFFPAGE TRUE
J 2
(-4000 2450);
DISPLAY 0.872340 (-4000 2450);
DISPLAY INVISIBLE (-4000 2450);
FORCEPROP 1 LAST COMMENT_BODY TRUE
J 2
(-3625 2475);
DISPLAY 0.872340 (-3625 2475);
PAINT GREEN (-3625 2475);
DISPLAY INVISIBLE (-3625 2475);
FORCEPROP 2 LAST PATH I13
J 0
(-3625 2650);
DISPLAY 1.021277 (-3625 2650);
DISPLAY INVISIBLE (-3625 2650);
FORCEADD Q_CAP..1
(2250 525);
FORCEPROP 1 LAST PART_NUMBER CH6103KEA00
J 0
(2300 375);
DISPLAY 0.978723 (2300 375);
DISPLAY INVISIBLE (2300 375);
FORCEPROP 1 LAST PACK_TYPE C0805
J 0
(2300 325);
DISPLAY 0.978723 (2300 325);
FORCEPROP 1 LAST TOLERANCE 10%
J 0
(2300 475);
DISPLAY 0.978723 (2300 475);
FORCEPROP 1 LAST VALUE 10UF
J 0
(2300 575);
DISPLAY 0.978723 (2300 575);
FORCEPROP 1 LAST VOLTAGE 16V
J 0
(2300 525);
DISPLAY 0.978723 (2300 525);
FORCEPROP 1 LAST MATERIAL X6S
J 0
(2300 425);
DISPLAY 0.978723 (2300 425);
FORCEPROP 1 LAST $LOCATION C34
J 0
(2300 625);
DISPLAY 0.978723 (2300 625);
FORCEPROP 1 LASTPIN (2250 625) $PN 1
J 0
(2260 605);
DISPLAY 0.787234 (2260 605);
FORCEPROP 1 LASTPIN (2250 425) $PN 2
J 0
(2260 405);
DISPLAY 0.787234 (2260 405);
FORCEPROP 2 LAST CDS_LIB pure_quanta
J 0
(2250 525);
PAINT MONO (2250 525);
DISPLAY INVISIBLE (2250 525);
FORCEPROP 2 LAST CDS_LOCATION C34
J 0
(2300 725);
DISPLAY 1.021277 (2300 725);
DISPLAY INVISIBLE (2300 725);
FORCEPROP 2 LAST $SEC 1
J 0
(2300 725);
DISPLAY 0.680851 (2300 725);
PAINT MONO (2300 725);
DISPLAY INVISIBLE (2300 725);
FORCEPROP 2 LAST CDS_SEC 1
J 0
(2300 725);
DISPLAY 1.021277 (2300 725);
DISPLAY INVISIBLE (2300 725);
FORCEPROP 1 LAST PATH I130
J 0
(2300 675);
DISPLAY 0.978723 (2300 675);
PAINT WHITE (2300 675);
DISPLAY INVISIBLE (2300 675);
FORCEADD TAP..1
(1650 2450);
FORCEPROP 3 LASTPIN (1600 2450) SIG_NAME M_F_CPU0_SB_DQS_DP<0>
J 0
(1610 2460);
DISPLAY 0.659574 (1610 2460);
PAINT MONO (1610 2460);
DISPLAY INVISIBLE (1610 2460);
FORCEPROP 1 LASTPIN (1600 2450) BN 0
J 0
(1588 2458);
DISPLAY 0.680851 (1588 2458);
PAINT GREEN (1588 2458);
FORCEPROP 2 LAST CDS_LIB standard
J 0
(1650 2450);
PAINT MONO (1650 2450);
DISPLAY INVISIBLE (1650 2450);
FORCEPROP 1 LAST BODY_TYPE PLUMBING
J 0
(1650 2500);
DISPLAY 0.872340 (1650 2500);
PAINT GREEN (1650 2500);
DISPLAY INVISIBLE (1650 2500);
FORCEPROP 1 LAST HDL_TAP TRUE
J 0
(1975 2325);
DISPLAY 0.872340 (1975 2325);
DISPLAY INVISIBLE (1975 2325);
FORCEPROP 1 LAST PATH I131
J 0
(1648 2450);
DISPLAY 0.872340 (1648 2450);
PAINT GREEN (1648 2450);
DISPLAY INVISIBLE (1648 2450);
FORCEADD TAP..1
(1650 2650);
FORCEPROP 3 LASTPIN (1600 2650) SIG_NAME M_F_CPU0_SB_DQS_DP<2>
J 0
(1610 2660);
DISPLAY 0.659574 (1610 2660);
PAINT MONO (1610 2660);
DISPLAY INVISIBLE (1610 2660);
FORCEPROP 1 LASTPIN (1600 2650) BN 2
J 0
(1588 2658);
DISPLAY 0.680851 (1588 2658);
PAINT GREEN (1588 2658);
FORCEPROP 2 LAST CDS_LIB standard
J 0
(1650 2650);
DISPLAY INVISIBLE (1650 2650);
FORCEPROP 1 LAST BODY_TYPE PLUMBING
J 0
(1650 2700);
DISPLAY 0.872340 (1650 2700);
PAINT GREEN (1650 2700);
DISPLAY INVISIBLE (1650 2700);
FORCEPROP 1 LAST HDL_TAP TRUE
J 0
(1975 2525);
DISPLAY 0.872340 (1975 2525);
DISPLAY INVISIBLE (1975 2525);
FORCEPROP 1 LAST PATH I132
J 0
(1648 2650);
DISPLAY 0.872340 (1648 2650);
PAINT GREEN (1648 2650);
DISPLAY INVISIBLE (1648 2650);
FORCEADD TAP..1
(1650 2550);
FORCEPROP 3 LASTPIN (1600 2550) SIG_NAME M_F_CPU0_SB_DQS_DP<1>
J 0
(1610 2560);
DISPLAY 0.659574 (1610 2560);
PAINT MONO (1610 2560);
DISPLAY INVISIBLE (1610 2560);
FORCEPROP 1 LASTPIN (1600 2550) BN 1
J 0
(1588 2558);
DISPLAY 0.680851 (1588 2558);
PAINT GREEN (1588 2558);
FORCEPROP 2 LAST CDS_LIB standard
J 0
(1650 2550);
DISPLAY INVISIBLE (1650 2550);
FORCEPROP 1 LAST BODY_TYPE PLUMBING
J 0
(1650 2600);
DISPLAY 0.872340 (1650 2600);
PAINT GREEN (1650 2600);
DISPLAY INVISIBLE (1650 2600);
FORCEPROP 1 LAST HDL_TAP TRUE
J 0
(1975 2425);
DISPLAY 0.872340 (1975 2425);
DISPLAY INVISIBLE (1975 2425);
FORCEPROP 1 LAST PATH I133
J 0
(1648 2550);
DISPLAY 0.872340 (1648 2550);
PAINT GREEN (1648 2550);
DISPLAY INVISIBLE (1648 2550);
FORCEADD TAP..1
(1650 2850);
FORCEPROP 3 LASTPIN (1600 2850) SIG_NAME M_F_CPU0_SB_DQS_DP<4>
J 0
(1610 2860);
DISPLAY 0.659574 (1610 2860);
PAINT MONO (1610 2860);
DISPLAY INVISIBLE (1610 2860);
FORCEPROP 1 LASTPIN (1600 2850) BN 4
J 0
(1588 2858);
DISPLAY 0.680851 (1588 2858);
PAINT GREEN (1588 2858);
FORCEPROP 2 LAST CDS_LIB standard
J 0
(1650 2850);
PAINT MONO (1650 2850);
DISPLAY INVISIBLE (1650 2850);
FORCEPROP 1 LAST BODY_TYPE PLUMBING
J 0
(1650 2900);
DISPLAY 0.872340 (1650 2900);
PAINT GREEN (1650 2900);
DISPLAY INVISIBLE (1650 2900);
FORCEPROP 1 LAST HDL_TAP TRUE
J 0
(1975 2725);
DISPLAY 0.872340 (1975 2725);
DISPLAY INVISIBLE (1975 2725);
FORCEPROP 1 LAST PATH I134
J 0
(1648 2850);
DISPLAY 0.872340 (1648 2850);
PAINT GREEN (1648 2850);
DISPLAY INVISIBLE (1648 2850);
FORCEADD TAP..1
(1650 2750);
FORCEPROP 3 LASTPIN (1600 2750) SIG_NAME M_F_CPU0_SB_DQS_DP<3>
J 0
(1610 2760);
DISPLAY 0.659574 (1610 2760);
PAINT MONO (1610 2760);
DISPLAY INVISIBLE (1610 2760);
FORCEPROP 1 LASTPIN (1600 2750) BN 3
J 0
(1588 2758);
DISPLAY 0.680851 (1588 2758);
PAINT GREEN (1588 2758);
FORCEPROP 2 LAST CDS_LIB standard
J 0
(1650 2750);
PAINT MONO (1650 2750);
DISPLAY INVISIBLE (1650 2750);
FORCEPROP 1 LAST BODY_TYPE PLUMBING
J 0
(1650 2800);
DISPLAY 0.872340 (1650 2800);
PAINT GREEN (1650 2800);
DISPLAY INVISIBLE (1650 2800);
FORCEPROP 1 LAST HDL_TAP TRUE
J 0
(1975 2625);
DISPLAY 0.872340 (1975 2625);
DISPLAY INVISIBLE (1975 2625);
FORCEPROP 1 LAST PATH I135
J 0
(1648 2750);
DISPLAY 0.872340 (1648 2750);
PAINT GREEN (1648 2750);
DISPLAY INVISIBLE (1648 2750);
FORCEADD TAP..1
(1825 2500);
FORCEPROP 3 LASTPIN (1775 2500) SIG_NAME M_F_CPU0_SB_DQS_DN<1>
J 0
(1785 2510);
DISPLAY 0.659574 (1785 2510);
PAINT MONO (1785 2510);
DISPLAY INVISIBLE (1785 2510);
FORCEPROP 1 LASTPIN (1775 2500) BN 1
J 0
(1763 2508);
DISPLAY 0.680851 (1763 2508);
PAINT GREEN (1763 2508);
FORCEPROP 2 LAST CDS_LIB standard
J 0
(1825 2500);
DISPLAY INVISIBLE (1825 2500);
FORCEPROP 1 LAST BODY_TYPE PLUMBING
J 0
(1825 2550);
DISPLAY 0.872340 (1825 2550);
PAINT GREEN (1825 2550);
DISPLAY INVISIBLE (1825 2550);
FORCEPROP 1 LAST HDL_TAP TRUE
J 0
(2150 2375);
DISPLAY 0.872340 (2150 2375);
DISPLAY INVISIBLE (2150 2375);
FORCEPROP 1 LAST PATH I136
J 0
(1823 2500);
DISPLAY 0.872340 (1823 2500);
PAINT GREEN (1823 2500);
DISPLAY INVISIBLE (1823 2500);
FORCEADD TAP..1
(1825 2600);
FORCEPROP 3 LASTPIN (1775 2600) SIG_NAME M_F_CPU0_SB_DQS_DN<2>
J 0
(1785 2610);
DISPLAY 0.659574 (1785 2610);
PAINT MONO (1785 2610);
DISPLAY INVISIBLE (1785 2610);
FORCEPROP 1 LASTPIN (1775 2600) BN 2
J 0
(1763 2608);
DISPLAY 0.680851 (1763 2608);
PAINT GREEN (1763 2608);
FORCEPROP 2 LAST CDS_LIB standard
J 0
(1825 2600);
DISPLAY INVISIBLE (1825 2600);
FORCEPROP 1 LAST BODY_TYPE PLUMBING
J 0
(1825 2650);
DISPLAY 0.872340 (1825 2650);
PAINT GREEN (1825 2650);
DISPLAY INVISIBLE (1825 2650);
FORCEPROP 1 LAST HDL_TAP TRUE
J 0
(2150 2475);
DISPLAY 0.872340 (2150 2475);
DISPLAY INVISIBLE (2150 2475);
FORCEPROP 1 LAST PATH I137
J 0
(1823 2600);
DISPLAY 0.872340 (1823 2600);
PAINT GREEN (1823 2600);
DISPLAY INVISIBLE (1823 2600);
FORCEADD TAP..1
(1825 2700);
FORCEPROP 3 LASTPIN (1775 2700) SIG_NAME M_F_CPU0_SB_DQS_DN<3>
J 0
(1785 2710);
DISPLAY 0.659574 (1785 2710);
PAINT MONO (1785 2710);
DISPLAY INVISIBLE (1785 2710);
FORCEPROP 1 LASTPIN (1775 2700) BN 3
J 0
(1763 2708);
DISPLAY 0.680851 (1763 2708);
PAINT GREEN (1763 2708);
FORCEPROP 2 LAST CDS_LIB standard
J 0
(1825 2700);
PAINT MONO (1825 2700);
DISPLAY INVISIBLE (1825 2700);
FORCEPROP 1 LAST BODY_TYPE PLUMBING
J 0
(1825 2750);
DISPLAY 0.872340 (1825 2750);
PAINT GREEN (1825 2750);
DISPLAY INVISIBLE (1825 2750);
FORCEPROP 1 LAST HDL_TAP TRUE
J 0
(2150 2575);
DISPLAY 0.872340 (2150 2575);
DISPLAY INVISIBLE (2150 2575);
FORCEPROP 1 LAST PATH I138
J 0
(1823 2700);
DISPLAY 0.872340 (1823 2700);
PAINT GREEN (1823 2700);
DISPLAY INVISIBLE (1823 2700);
FORCEADD TAP..1
(1825 2800);
FORCEPROP 3 LASTPIN (1775 2800) SIG_NAME M_F_CPU0_SB_DQS_DN<4>
J 0
(1785 2810);
DISPLAY 0.659574 (1785 2810);
PAINT MONO (1785 2810);
DISPLAY INVISIBLE (1785 2810);
FORCEPROP 1 LASTPIN (1775 2800) BN 4
J 0
(1763 2808);
DISPLAY 0.680851 (1763 2808);
PAINT GREEN (1763 2808);
FORCEPROP 2 LAST CDS_LIB standard
J 0
(1825 2800);
PAINT MONO (1825 2800);
DISPLAY INVISIBLE (1825 2800);
FORCEPROP 1 LAST BODY_TYPE PLUMBING
J 0
(1825 2850);
DISPLAY 0.872340 (1825 2850);
PAINT GREEN (1825 2850);
DISPLAY INVISIBLE (1825 2850);
FORCEPROP 1 LAST HDL_TAP TRUE
J 0
(2150 2675);
DISPLAY 0.872340 (2150 2675);
DISPLAY INVISIBLE (2150 2675);
FORCEPROP 1 LAST PATH I139
J 0
(1823 2800);
DISPLAY 0.872340 (1823 2800);
PAINT GREEN (1823 2800);
DISPLAY INVISIBLE (1823 2800);
FORCEADD OFFPAGE..1
(-3675 3150);
FORCEPROP 2 LAST $XR0 25 
J 0
(-3896 3150);
DISPLAY 0.638298 (-3896 3150);
PAINT MONO (-3896 3150);
FORCEPROP 2 LAST CDS_LIB standard
J 0
(-3675 3150);
PAINT MONO (-3675 3150);
DISPLAY INVISIBLE (-3675 3150);
FORCEPROP 1 LAST OFFPAGE TRUE
J 0
(-3350 3025);
DISPLAY 0.872340 (-3350 3025);
DISPLAY INVISIBLE (-3350 3025);
FORCEPROP 1 LAST COMMENT_BODY TRUE
J 0
(-3550 3050);
DISPLAY 0.872340 (-3550 3050);
PAINT GREEN (-3550 3050);
DISPLAY INVISIBLE (-3550 3050);
FORCEPROP 2 LAST PATH I14
J 0
(-3625 3225);
DISPLAY 1.021277 (-3625 3225);
DISPLAY INVISIBLE (-3625 3225);
FORCEADD TAP..1
(1825 2900);
FORCEPROP 3 LASTPIN (1775 2900) SIG_NAME M_F_CPU0_SB_DQS_DN<5>
J 0
(1785 2910);
DISPLAY 0.659574 (1785 2910);
PAINT MONO (1785 2910);
DISPLAY INVISIBLE (1785 2910);
FORCEPROP 1 LASTPIN (1775 2900) BN 5
J 0
(1763 2908);
DISPLAY 0.680851 (1763 2908);
PAINT GREEN (1763 2908);
FORCEPROP 2 LAST CDS_LIB standard
J 0
(1825 2900);
DISPLAY INVISIBLE (1825 2900);
FORCEPROP 1 LAST BODY_TYPE PLUMBING
J 0
(1825 2950);
DISPLAY 0.872340 (1825 2950);
PAINT GREEN (1825 2950);
DISPLAY INVISIBLE (1825 2950);
FORCEPROP 1 LAST HDL_TAP TRUE
J 0
(2150 2775);
DISPLAY 0.872340 (2150 2775);
DISPLAY INVISIBLE (2150 2775);
FORCEPROP 1 LAST PATH I140
J 0
(1823 2900);
DISPLAY 0.872340 (1823 2900);
PAINT GREEN (1823 2900);
DISPLAY INVISIBLE (1823 2900);
FORCEADD TAP..1
(1650 2950);
FORCEPROP 3 LASTPIN (1600 2950) SIG_NAME M_F_CPU0_SB_DQS_DP<5>
J 0
(1610 2960);
DISPLAY 0.659574 (1610 2960);
PAINT MONO (1610 2960);
DISPLAY INVISIBLE (1610 2960);
FORCEPROP 1 LASTPIN (1600 2950) BN 5
J 0
(1588 2958);
DISPLAY 0.680851 (1588 2958);
PAINT GREEN (1588 2958);
FORCEPROP 2 LAST CDS_LIB standard
J 0
(1650 2950);
DISPLAY INVISIBLE (1650 2950);
FORCEPROP 1 LAST BODY_TYPE PLUMBING
J 0
(1650 3000);
DISPLAY 0.872340 (1650 3000);
PAINT GREEN (1650 3000);
DISPLAY INVISIBLE (1650 3000);
FORCEPROP 1 LAST HDL_TAP TRUE
J 0
(1975 2825);
DISPLAY 0.872340 (1975 2825);
DISPLAY INVISIBLE (1975 2825);
FORCEPROP 1 LAST PATH I141
J 0
(1648 2950);
DISPLAY 0.872340 (1648 2950);
PAINT GREEN (1648 2950);
DISPLAY INVISIBLE (1648 2950);
FORCEADD TAP..1
(1650 3150);
FORCEPROP 3 LASTPIN (1600 3150) SIG_NAME M_F_CPU0_SB_DQS_DP<7>
J 0
(1610 3160);
DISPLAY 0.659574 (1610 3160);
PAINT MONO (1610 3160);
DISPLAY INVISIBLE (1610 3160);
FORCEPROP 1 LASTPIN (1600 3150) BN 7
J 0
(1588 3158);
DISPLAY 0.680851 (1588 3158);
PAINT GREEN (1588 3158);
FORCEPROP 2 LAST CDS_LIB standard
J 0
(1650 3150);
DISPLAY INVISIBLE (1650 3150);
FORCEPROP 1 LAST BODY_TYPE PLUMBING
J 0
(1650 3200);
DISPLAY 0.872340 (1650 3200);
PAINT GREEN (1650 3200);
DISPLAY INVISIBLE (1650 3200);
FORCEPROP 1 LAST HDL_TAP TRUE
J 0
(1975 3025);
DISPLAY 0.872340 (1975 3025);
DISPLAY INVISIBLE (1975 3025);
FORCEPROP 1 LAST PATH I142
J 0
(1648 3150);
DISPLAY 0.872340 (1648 3150);
PAINT GREEN (1648 3150);
DISPLAY INVISIBLE (1648 3150);
FORCEADD TAP..1
(1650 3050);
FORCEPROP 3 LASTPIN (1600 3050) SIG_NAME M_F_CPU0_SB_DQS_DP<6>
J 0
(1610 3060);
DISPLAY 0.659574 (1610 3060);
PAINT MONO (1610 3060);
DISPLAY INVISIBLE (1610 3060);
FORCEPROP 1 LASTPIN (1600 3050) BN 6
J 0
(1588 3058);
DISPLAY 0.680851 (1588 3058);
PAINT GREEN (1588 3058);
FORCEPROP 2 LAST CDS_LIB standard
J 0
(1650 3050);
DISPLAY INVISIBLE (1650 3050);
FORCEPROP 1 LAST BODY_TYPE PLUMBING
J 0
(1650 3100);
DISPLAY 0.872340 (1650 3100);
PAINT GREEN (1650 3100);
DISPLAY INVISIBLE (1650 3100);
FORCEPROP 1 LAST HDL_TAP TRUE
J 0
(1975 2925);
DISPLAY 0.872340 (1975 2925);
DISPLAY INVISIBLE (1975 2925);
FORCEPROP 1 LAST PATH I143
J 0
(1648 3050);
DISPLAY 0.872340 (1648 3050);
PAINT GREEN (1648 3050);
DISPLAY INVISIBLE (1648 3050);
FORCEADD TAP..1
(1650 3350);
FORCEPROP 3 LASTPIN (1600 3350) SIG_NAME M_F_CPU0_SB_DQS_DP<9>
J 0
(1610 3360);
DISPLAY 0.659574 (1610 3360);
PAINT MONO (1610 3360);
DISPLAY INVISIBLE (1610 3360);
FORCEPROP 1 LASTPIN (1600 3350) BN 9
J 0
(1588 3358);
DISPLAY 0.680851 (1588 3358);
PAINT GREEN (1588 3358);
FORCEPROP 2 LAST CDS_LIB standard
J 0
(1650 3350);
DISPLAY INVISIBLE (1650 3350);
FORCEPROP 1 LAST BODY_TYPE PLUMBING
J 0
(1650 3400);
DISPLAY 0.872340 (1650 3400);
PAINT GREEN (1650 3400);
DISPLAY INVISIBLE (1650 3400);
FORCEPROP 1 LAST HDL_TAP TRUE
J 0
(1975 3225);
DISPLAY 0.872340 (1975 3225);
DISPLAY INVISIBLE (1975 3225);
FORCEPROP 1 LAST PATH I144
J 0
(1648 3350);
DISPLAY 0.872340 (1648 3350);
PAINT GREEN (1648 3350);
DISPLAY INVISIBLE (1648 3350);
FORCEADD TAP..1
(1650 3250);
FORCEPROP 3 LASTPIN (1600 3250) SIG_NAME M_F_CPU0_SB_DQS_DP<8>
J 0
(1610 3260);
DISPLAY 0.659574 (1610 3260);
PAINT MONO (1610 3260);
DISPLAY INVISIBLE (1610 3260);
FORCEPROP 1 LASTPIN (1600 3250) BN 8
J 0
(1588 3258);
DISPLAY 0.680851 (1588 3258);
PAINT GREEN (1588 3258);
FORCEPROP 2 LAST CDS_LIB standard
J 0
(1650 3250);
DISPLAY INVISIBLE (1650 3250);
FORCEPROP 1 LAST BODY_TYPE PLUMBING
J 0
(1650 3300);
DISPLAY 0.872340 (1650 3300);
PAINT GREEN (1650 3300);
DISPLAY INVISIBLE (1650 3300);
FORCEPROP 1 LAST HDL_TAP TRUE
J 0
(1975 3125);
DISPLAY 0.872340 (1975 3125);
DISPLAY INVISIBLE (1975 3125);
FORCEPROP 1 LAST PATH I145
J 0
(1648 3250);
DISPLAY 0.872340 (1648 3250);
PAINT GREEN (1648 3250);
DISPLAY INVISIBLE (1648 3250);
FORCEADD TAP..1
(1825 3000);
FORCEPROP 3 LASTPIN (1775 3000) SIG_NAME M_F_CPU0_SB_DQS_DN<6>
J 0
(1785 3010);
DISPLAY 0.659574 (1785 3010);
PAINT MONO (1785 3010);
DISPLAY INVISIBLE (1785 3010);
FORCEPROP 1 LASTPIN (1775 3000) BN 6
J 0
(1763 3008);
DISPLAY 0.680851 (1763 3008);
PAINT GREEN (1763 3008);
FORCEPROP 2 LAST CDS_LIB standard
J 0
(1825 3000);
DISPLAY INVISIBLE (1825 3000);
FORCEPROP 1 LAST BODY_TYPE PLUMBING
J 0
(1825 3050);
DISPLAY 0.872340 (1825 3050);
PAINT GREEN (1825 3050);
DISPLAY INVISIBLE (1825 3050);
FORCEPROP 1 LAST HDL_TAP TRUE
J 0
(2150 2875);
DISPLAY 0.872340 (2150 2875);
DISPLAY INVISIBLE (2150 2875);
FORCEPROP 1 LAST PATH I146
J 0
(1823 3000);
DISPLAY 0.872340 (1823 3000);
PAINT GREEN (1823 3000);
DISPLAY INVISIBLE (1823 3000);
FORCEADD TAP..1
(1825 3100);
FORCEPROP 3 LASTPIN (1775 3100) SIG_NAME M_F_CPU0_SB_DQS_DN<7>
J 0
(1785 3110);
DISPLAY 0.659574 (1785 3110);
PAINT MONO (1785 3110);
DISPLAY INVISIBLE (1785 3110);
FORCEPROP 1 LASTPIN (1775 3100) BN 7
J 0
(1763 3108);
DISPLAY 0.680851 (1763 3108);
PAINT GREEN (1763 3108);
FORCEPROP 2 LAST CDS_LIB standard
J 0
(1825 3100);
DISPLAY INVISIBLE (1825 3100);
FORCEPROP 1 LAST BODY_TYPE PLUMBING
J 0
(1825 3150);
DISPLAY 0.872340 (1825 3150);
PAINT GREEN (1825 3150);
DISPLAY INVISIBLE (1825 3150);
FORCEPROP 1 LAST HDL_TAP TRUE
J 0
(2150 2975);
DISPLAY 0.872340 (2150 2975);
DISPLAY INVISIBLE (2150 2975);
FORCEPROP 1 LAST PATH I147
J 0
(1823 3100);
DISPLAY 0.872340 (1823 3100);
PAINT GREEN (1823 3100);
DISPLAY INVISIBLE (1823 3100);
FORCEADD TAP..1
(1825 3300);
FORCEPROP 3 LASTPIN (1775 3300) SIG_NAME M_F_CPU0_SB_DQS_DN<9>
J 0
(1785 3310);
DISPLAY 0.659574 (1785 3310);
PAINT MONO (1785 3310);
DISPLAY INVISIBLE (1785 3310);
FORCEPROP 1 LASTPIN (1775 3300) BN 9
J 0
(1763 3308);
DISPLAY 0.680851 (1763 3308);
PAINT GREEN (1763 3308);
FORCEPROP 2 LAST CDS_LIB standard
J 0
(1825 3300);
DISPLAY INVISIBLE (1825 3300);
FORCEPROP 1 LAST BODY_TYPE PLUMBING
J 0
(1825 3350);
DISPLAY 0.872340 (1825 3350);
PAINT GREEN (1825 3350);
DISPLAY INVISIBLE (1825 3350);
FORCEPROP 1 LAST HDL_TAP TRUE
J 0
(2150 3175);
DISPLAY 0.872340 (2150 3175);
DISPLAY INVISIBLE (2150 3175);
FORCEPROP 1 LAST PATH I148
J 0
(1823 3300);
DISPLAY 0.872340 (1823 3300);
PAINT GREEN (1823 3300);
DISPLAY INVISIBLE (1823 3300);
FORCEADD TAP..1
(1825 3200);
FORCEPROP 3 LASTPIN (1775 3200) SIG_NAME M_F_CPU0_SB_DQS_DN<8>
J 0
(1785 3210);
DISPLAY 0.659574 (1785 3210);
PAINT MONO (1785 3210);
DISPLAY INVISIBLE (1785 3210);
FORCEPROP 1 LASTPIN (1775 3200) BN 8
J 0
(1763 3208);
DISPLAY 0.680851 (1763 3208);
PAINT GREEN (1763 3208);
FORCEPROP 2 LAST CDS_LIB standard
J 0
(1825 3200);
DISPLAY INVISIBLE (1825 3200);
FORCEPROP 1 LAST BODY_TYPE PLUMBING
J 0
(1825 3250);
DISPLAY 0.872340 (1825 3250);
PAINT GREEN (1825 3250);
DISPLAY INVISIBLE (1825 3250);
FORCEPROP 1 LAST HDL_TAP TRUE
J 0
(2150 3075);
DISPLAY 0.872340 (2150 3075);
DISPLAY INVISIBLE (2150 3075);
FORCEPROP 1 LAST PATH I149
J 0
(1823 3200);
DISPLAY 0.872340 (1823 3200);
PAINT GREEN (1823 3200);
DISPLAY INVISIBLE (1823 3200);
FORCEADD OFFPAGE..1
(-3675 3100);
FORCEPROP 2 LAST $XR0 25 
J 0
(-3896 3100);
DISPLAY 0.638298 (-3896 3100);
PAINT MONO (-3896 3100);
FORCEPROP 2 LAST CDS_LIB standard
J 0
(-3675 3100);
PAINT MONO (-3675 3100);
DISPLAY INVISIBLE (-3675 3100);
FORCEPROP 1 LAST OFFPAGE TRUE
J 0
(-3350 2975);
DISPLAY 0.872340 (-3350 2975);
DISPLAY INVISIBLE (-3350 2975);
FORCEPROP 1 LAST COMMENT_BODY TRUE
J 0
(-3550 3000);
DISPLAY 0.872340 (-3550 3000);
PAINT GREEN (-3550 3000);
DISPLAY INVISIBLE (-3550 3000);
FORCEPROP 2 LAST PATH I15
J 0
(-3625 3175);
DISPLAY 1.021277 (-3625 3175);
DISPLAY INVISIBLE (-3625 3175);
FORCEADD TAP..1
(1650 3500);
FORCEPROP 3 LASTPIN (1600 3500) SIG_NAME M_F_CPU0_SA_DQS_DP<0>
J 0
(1610 3510);
DISPLAY 0.659574 (1610 3510);
PAINT MONO (1610 3510);
DISPLAY INVISIBLE (1610 3510);
FORCEPROP 1 LASTPIN (1600 3500) BN 0
J 0
(1588 3508);
DISPLAY 0.680851 (1588 3508);
PAINT GREEN (1588 3508);
FORCEPROP 2 LAST CDS_LIB standard
J 0
(1650 3500);
PAINT MONO (1650 3500);
DISPLAY INVISIBLE (1650 3500);
FORCEPROP 1 LAST BODY_TYPE PLUMBING
J 0
(1650 3550);
DISPLAY 0.872340 (1650 3550);
PAINT GREEN (1650 3550);
DISPLAY INVISIBLE (1650 3550);
FORCEPROP 1 LAST HDL_TAP TRUE
J 0
(1975 3375);
DISPLAY 0.872340 (1975 3375);
DISPLAY INVISIBLE (1975 3375);
FORCEPROP 1 LAST PATH I150
J 0
(1648 3500);
DISPLAY 0.872340 (1648 3500);
PAINT GREEN (1648 3500);
DISPLAY INVISIBLE (1648 3500);
FORCEADD TAP..1
(1650 3600);
FORCEPROP 3 LASTPIN (1600 3600) SIG_NAME M_F_CPU0_SA_DQS_DP<1>
J 0
(1610 3610);
DISPLAY 0.659574 (1610 3610);
PAINT MONO (1610 3610);
DISPLAY INVISIBLE (1610 3610);
FORCEPROP 1 LASTPIN (1600 3600) BN 1
J 0
(1588 3608);
DISPLAY 0.680851 (1588 3608);
PAINT GREEN (1588 3608);
FORCEPROP 2 LAST CDS_LIB standard
J 0
(1650 3600);
DISPLAY INVISIBLE (1650 3600);
FORCEPROP 1 LAST BODY_TYPE PLUMBING
J 0
(1650 3650);
DISPLAY 0.872340 (1650 3650);
PAINT GREEN (1650 3650);
DISPLAY INVISIBLE (1650 3650);
FORCEPROP 1 LAST HDL_TAP TRUE
J 0
(1975 3475);
DISPLAY 0.872340 (1975 3475);
DISPLAY INVISIBLE (1975 3475);
FORCEPROP 1 LAST PATH I151
J 0
(1648 3600);
DISPLAY 0.872340 (1648 3600);
PAINT GREEN (1648 3600);
DISPLAY INVISIBLE (1648 3600);
FORCEADD TAP..1
(1650 3700);
FORCEPROP 3 LASTPIN (1600 3700) SIG_NAME M_F_CPU0_SA_DQS_DP<2>
J 0
(1610 3710);
DISPLAY 0.659574 (1610 3710);
PAINT MONO (1610 3710);
DISPLAY INVISIBLE (1610 3710);
FORCEPROP 1 LASTPIN (1600 3700) BN 2
J 0
(1588 3708);
DISPLAY 0.680851 (1588 3708);
PAINT GREEN (1588 3708);
FORCEPROP 2 LAST CDS_LIB standard
J 0
(1650 3700);
DISPLAY INVISIBLE (1650 3700);
FORCEPROP 1 LAST BODY_TYPE PLUMBING
J 0
(1650 3750);
DISPLAY 0.872340 (1650 3750);
PAINT GREEN (1650 3750);
DISPLAY INVISIBLE (1650 3750);
FORCEPROP 1 LAST HDL_TAP TRUE
J 0
(1975 3575);
DISPLAY 0.872340 (1975 3575);
DISPLAY INVISIBLE (1975 3575);
FORCEPROP 1 LAST PATH I152
J 0
(1648 3700);
DISPLAY 0.872340 (1648 3700);
PAINT GREEN (1648 3700);
DISPLAY INVISIBLE (1648 3700);
FORCEADD TAP..1
(1650 3900);
FORCEPROP 3 LASTPIN (1600 3900) SIG_NAME M_F_CPU0_SA_DQS_DP<4>
J 0
(1610 3910);
DISPLAY 0.659574 (1610 3910);
PAINT MONO (1610 3910);
DISPLAY INVISIBLE (1610 3910);
FORCEPROP 1 LASTPIN (1600 3900) BN 4
J 0
(1588 3908);
DISPLAY 0.680851 (1588 3908);
PAINT GREEN (1588 3908);
FORCEPROP 2 LAST CDS_LIB standard
J 0
(1650 3900);
PAINT MONO (1650 3900);
DISPLAY INVISIBLE (1650 3900);
FORCEPROP 1 LAST BODY_TYPE PLUMBING
J 0
(1650 3950);
DISPLAY 0.872340 (1650 3950);
PAINT GREEN (1650 3950);
DISPLAY INVISIBLE (1650 3950);
FORCEPROP 1 LAST HDL_TAP TRUE
J 0
(1975 3775);
DISPLAY 0.872340 (1975 3775);
DISPLAY INVISIBLE (1975 3775);
FORCEPROP 1 LAST PATH I153
J 0
(1648 3900);
DISPLAY 0.872340 (1648 3900);
PAINT GREEN (1648 3900);
DISPLAY INVISIBLE (1648 3900);
FORCEADD TAP..1
(1650 3800);
FORCEPROP 3 LASTPIN (1600 3800) SIG_NAME M_F_CPU0_SA_DQS_DP<3>
J 0
(1610 3810);
DISPLAY 0.659574 (1610 3810);
PAINT MONO (1610 3810);
DISPLAY INVISIBLE (1610 3810);
FORCEPROP 1 LASTPIN (1600 3800) BN 3
J 0
(1588 3808);
DISPLAY 0.680851 (1588 3808);
PAINT GREEN (1588 3808);
FORCEPROP 2 LAST CDS_LIB standard
J 0
(1650 3800);
PAINT MONO (1650 3800);
DISPLAY INVISIBLE (1650 3800);
FORCEPROP 1 LAST BODY_TYPE PLUMBING
J 0
(1650 3850);
DISPLAY 0.872340 (1650 3850);
PAINT GREEN (1650 3850);
DISPLAY INVISIBLE (1650 3850);
FORCEPROP 1 LAST HDL_TAP TRUE
J 0
(1975 3675);
DISPLAY 0.872340 (1975 3675);
DISPLAY INVISIBLE (1975 3675);
FORCEPROP 1 LAST PATH I154
J 0
(1648 3800);
DISPLAY 0.872340 (1648 3800);
PAINT GREEN (1648 3800);
DISPLAY INVISIBLE (1648 3800);
FORCEADD TAP..1
(1825 3450);
FORCEPROP 3 LASTPIN (1775 3450) SIG_NAME M_F_CPU0_SA_DQS_DN<0>
J 0
(1785 3460);
DISPLAY 0.659574 (1785 3460);
PAINT MONO (1785 3460);
DISPLAY INVISIBLE (1785 3460);
FORCEPROP 1 LASTPIN (1775 3450) BN 0
J 0
(1763 3458);
DISPLAY 0.680851 (1763 3458);
PAINT GREEN (1763 3458);
FORCEPROP 2 LAST CDS_LIB standard
J 0
(1825 3450);
PAINT MONO (1825 3450);
DISPLAY INVISIBLE (1825 3450);
FORCEPROP 1 LAST BODY_TYPE PLUMBING
J 0
(1825 3500);
DISPLAY 0.872340 (1825 3500);
PAINT GREEN (1825 3500);
DISPLAY INVISIBLE (1825 3500);
FORCEPROP 1 LAST HDL_TAP TRUE
J 0
(2150 3325);
DISPLAY 0.872340 (2150 3325);
DISPLAY INVISIBLE (2150 3325);
FORCEPROP 1 LAST PATH I155
J 0
(1823 3450);
DISPLAY 0.872340 (1823 3450);
PAINT GREEN (1823 3450);
DISPLAY INVISIBLE (1823 3450);
FORCEADD TAP..1
(1825 3550);
FORCEPROP 3 LASTPIN (1775 3550) SIG_NAME M_F_CPU0_SA_DQS_DN<1>
J 0
(1785 3560);
DISPLAY 0.659574 (1785 3560);
PAINT MONO (1785 3560);
DISPLAY INVISIBLE (1785 3560);
FORCEPROP 1 LASTPIN (1775 3550) BN 1
J 0
(1763 3558);
DISPLAY 0.680851 (1763 3558);
PAINT GREEN (1763 3558);
FORCEPROP 2 LAST CDS_LIB standard
J 0
(1825 3550);
DISPLAY INVISIBLE (1825 3550);
FORCEPROP 1 LAST BODY_TYPE PLUMBING
J 0
(1825 3600);
DISPLAY 0.872340 (1825 3600);
PAINT GREEN (1825 3600);
DISPLAY INVISIBLE (1825 3600);
FORCEPROP 1 LAST HDL_TAP TRUE
J 0
(2150 3425);
DISPLAY 0.872340 (2150 3425);
DISPLAY INVISIBLE (2150 3425);
FORCEPROP 1 LAST PATH I156
J 0
(1823 3550);
DISPLAY 0.872340 (1823 3550);
PAINT GREEN (1823 3550);
DISPLAY INVISIBLE (1823 3550);
FORCEADD TAP..1
(1825 3650);
FORCEPROP 3 LASTPIN (1775 3650) SIG_NAME M_F_CPU0_SA_DQS_DN<2>
J 0
(1785 3660);
DISPLAY 0.659574 (1785 3660);
PAINT MONO (1785 3660);
DISPLAY INVISIBLE (1785 3660);
FORCEPROP 1 LASTPIN (1775 3650) BN 2
J 0
(1763 3658);
DISPLAY 0.680851 (1763 3658);
PAINT GREEN (1763 3658);
FORCEPROP 2 LAST CDS_LIB standard
J 0
(1825 3650);
DISPLAY INVISIBLE (1825 3650);
FORCEPROP 1 LAST BODY_TYPE PLUMBING
J 0
(1825 3700);
DISPLAY 0.872340 (1825 3700);
PAINT GREEN (1825 3700);
DISPLAY INVISIBLE (1825 3700);
FORCEPROP 1 LAST HDL_TAP TRUE
J 0
(2150 3525);
DISPLAY 0.872340 (2150 3525);
DISPLAY INVISIBLE (2150 3525);
FORCEPROP 1 LAST PATH I157
J 0
(1823 3650);
DISPLAY 0.872340 (1823 3650);
PAINT GREEN (1823 3650);
DISPLAY INVISIBLE (1823 3650);
FORCEADD TAP..1
(1825 3750);
FORCEPROP 3 LASTPIN (1775 3750) SIG_NAME M_F_CPU0_SA_DQS_DN<3>
J 0
(1785 3760);
DISPLAY 0.659574 (1785 3760);
PAINT MONO (1785 3760);
DISPLAY INVISIBLE (1785 3760);
FORCEPROP 1 LASTPIN (1775 3750) BN 3
J 0
(1763 3758);
DISPLAY 0.680851 (1763 3758);
PAINT GREEN (1763 3758);
FORCEPROP 2 LAST CDS_LIB standard
J 0
(1825 3750);
PAINT MONO (1825 3750);
DISPLAY INVISIBLE (1825 3750);
FORCEPROP 1 LAST BODY_TYPE PLUMBING
J 0
(1825 3800);
DISPLAY 0.872340 (1825 3800);
PAINT GREEN (1825 3800);
DISPLAY INVISIBLE (1825 3800);
FORCEPROP 1 LAST HDL_TAP TRUE
J 0
(2150 3625);
DISPLAY 0.872340 (2150 3625);
DISPLAY INVISIBLE (2150 3625);
FORCEPROP 1 LAST PATH I158
J 0
(1823 3750);
DISPLAY 0.872340 (1823 3750);
PAINT GREEN (1823 3750);
DISPLAY INVISIBLE (1823 3750);
FORCEADD TAP..1
(1825 3950);
FORCEPROP 3 LASTPIN (1775 3950) SIG_NAME M_F_CPU0_SA_DQS_DN<5>
J 0
(1785 3960);
DISPLAY 0.659574 (1785 3960);
PAINT MONO (1785 3960);
DISPLAY INVISIBLE (1785 3960);
FORCEPROP 1 LASTPIN (1775 3950) BN 5
J 0
(1763 3958);
DISPLAY 0.680851 (1763 3958);
PAINT GREEN (1763 3958);
FORCEPROP 2 LAST CDS_LIB standard
J 0
(1825 3950);
DISPLAY INVISIBLE (1825 3950);
FORCEPROP 1 LAST BODY_TYPE PLUMBING
J 0
(1825 4000);
DISPLAY 0.872340 (1825 4000);
PAINT GREEN (1825 4000);
DISPLAY INVISIBLE (1825 4000);
FORCEPROP 1 LAST HDL_TAP TRUE
J 0
(2150 3825);
DISPLAY 0.872340 (2150 3825);
DISPLAY INVISIBLE (2150 3825);
FORCEPROP 1 LAST PATH I159
J 0
(1823 3950);
DISPLAY 0.872340 (1823 3950);
PAINT GREEN (1823 3950);
DISPLAY INVISIBLE (1823 3950);
FORCEADD OFFPAGE..3
R 2
(-3675 3025);
FORCEPROP 2 LAST $XR1 93 
J 0
(-4014 3025);
DISPLAY 0.638298 (-4014 3025);
PAINT MONO (-4014 3025);
FORCEPROP 2 LAST $XR0 25 
J 0
(-3924 3025);
DISPLAY 0.638298 (-3924 3025);
PAINT MONO (-3924 3025);
FORCEPROP 2 LAST CDS_LIB standard
J 0
(-3675 3025);
PAINT MONO (-3675 3025);
DISPLAY INVISIBLE (-3675 3025);
FORCEPROP 1 LAST OFFPAGE TRUE
J 2
(-4000 2900);
DISPLAY 0.872340 (-4000 2900);
DISPLAY INVISIBLE (-4000 2900);
FORCEPROP 1 LAST COMMENT_BODY TRUE
J 2
(-3625 2925);
DISPLAY 0.872340 (-3625 2925);
PAINT GREEN (-3625 2925);
DISPLAY INVISIBLE (-3625 2925);
FORCEPROP 2 LAST PATH I16
J 0
(-3625 3100);
DISPLAY 1.021277 (-3625 3100);
DISPLAY INVISIBLE (-3625 3100);
FORCEADD TAP..1
(1825 3850);
FORCEPROP 3 LASTPIN (1775 3850) SIG_NAME M_F_CPU0_SA_DQS_DN<4>
J 0
(1785 3860);
DISPLAY 0.659574 (1785 3860);
PAINT MONO (1785 3860);
DISPLAY INVISIBLE (1785 3860);
FORCEPROP 1 LASTPIN (1775 3850) BN 4
J 0
(1763 3858);
DISPLAY 0.680851 (1763 3858);
PAINT GREEN (1763 3858);
FORCEPROP 2 LAST CDS_LIB standard
J 0
(1825 3850);
PAINT MONO (1825 3850);
DISPLAY INVISIBLE (1825 3850);
FORCEPROP 1 LAST BODY_TYPE PLUMBING
J 0
(1825 3900);
DISPLAY 0.872340 (1825 3900);
PAINT GREEN (1825 3900);
DISPLAY INVISIBLE (1825 3900);
FORCEPROP 1 LAST HDL_TAP TRUE
J 0
(2150 3725);
DISPLAY 0.872340 (2150 3725);
DISPLAY INVISIBLE (2150 3725);
FORCEPROP 1 LAST PATH I160
J 0
(1823 3850);
DISPLAY 0.872340 (1823 3850);
PAINT GREEN (1823 3850);
DISPLAY INVISIBLE (1823 3850);
FORCEADD TAP..1
(1650 4000);
FORCEPROP 3 LASTPIN (1600 4000) SIG_NAME M_F_CPU0_SA_DQS_DP<5>
J 0
(1610 4010);
DISPLAY 0.659574 (1610 4010);
PAINT MONO (1610 4010);
DISPLAY INVISIBLE (1610 4010);
FORCEPROP 1 LASTPIN (1600 4000) BN 5
J 0
(1588 4008);
DISPLAY 0.680851 (1588 4008);
PAINT GREEN (1588 4008);
FORCEPROP 2 LAST CDS_LIB standard
J 0
(1650 4000);
DISPLAY INVISIBLE (1650 4000);
FORCEPROP 1 LAST BODY_TYPE PLUMBING
J 0
(1650 4050);
DISPLAY 0.872340 (1650 4050);
PAINT GREEN (1650 4050);
DISPLAY INVISIBLE (1650 4050);
FORCEPROP 1 LAST HDL_TAP TRUE
J 0
(1975 3875);
DISPLAY 0.872340 (1975 3875);
DISPLAY INVISIBLE (1975 3875);
FORCEPROP 1 LAST PATH I161
J 0
(1648 4000);
DISPLAY 0.872340 (1648 4000);
PAINT GREEN (1648 4000);
DISPLAY INVISIBLE (1648 4000);
FORCEADD TAP..1
(1650 4100);
FORCEPROP 3 LASTPIN (1600 4100) SIG_NAME M_F_CPU0_SA_DQS_DP<6>
J 0
(1610 4110);
DISPLAY 0.659574 (1610 4110);
PAINT MONO (1610 4110);
DISPLAY INVISIBLE (1610 4110);
FORCEPROP 1 LASTPIN (1600 4100) BN 6
J 0
(1588 4108);
DISPLAY 0.680851 (1588 4108);
PAINT GREEN (1588 4108);
FORCEPROP 2 LAST CDS_LIB standard
J 0
(1650 4100);
DISPLAY INVISIBLE (1650 4100);
FORCEPROP 1 LAST BODY_TYPE PLUMBING
J 0
(1650 4150);
DISPLAY 0.872340 (1650 4150);
PAINT GREEN (1650 4150);
DISPLAY INVISIBLE (1650 4150);
FORCEPROP 1 LAST HDL_TAP TRUE
J 0
(1975 3975);
DISPLAY 0.872340 (1975 3975);
DISPLAY INVISIBLE (1975 3975);
FORCEPROP 1 LAST PATH I162
J 0
(1648 4100);
DISPLAY 0.872340 (1648 4100);
PAINT GREEN (1648 4100);
DISPLAY INVISIBLE (1648 4100);
FORCEADD TAP..1
(1650 4200);
FORCEPROP 3 LASTPIN (1600 4200) SIG_NAME M_F_CPU0_SA_DQS_DP<7>
J 0
(1610 4210);
DISPLAY 0.659574 (1610 4210);
PAINT MONO (1610 4210);
DISPLAY INVISIBLE (1610 4210);
FORCEPROP 1 LASTPIN (1600 4200) BN 7
J 0
(1588 4208);
DISPLAY 0.680851 (1588 4208);
PAINT GREEN (1588 4208);
FORCEPROP 2 LAST CDS_LIB standard
J 0
(1650 4200);
DISPLAY INVISIBLE (1650 4200);
FORCEPROP 1 LAST BODY_TYPE PLUMBING
J 0
(1650 4250);
DISPLAY 0.872340 (1650 4250);
PAINT GREEN (1650 4250);
DISPLAY INVISIBLE (1650 4250);
FORCEPROP 1 LAST HDL_TAP TRUE
J 0
(1975 4075);
DISPLAY 0.872340 (1975 4075);
DISPLAY INVISIBLE (1975 4075);
FORCEPROP 1 LAST PATH I163
J 0
(1648 4200);
DISPLAY 0.872340 (1648 4200);
PAINT GREEN (1648 4200);
DISPLAY INVISIBLE (1648 4200);
FORCEADD TAP..1
(1650 4400);
FORCEPROP 3 LASTPIN (1600 4400) SIG_NAME M_F_CPU0_SA_DQS_DP<9>
J 0
(1610 4410);
DISPLAY 0.659574 (1610 4410);
PAINT MONO (1610 4410);
DISPLAY INVISIBLE (1610 4410);
FORCEPROP 1 LASTPIN (1600 4400) BN 9
J 0
(1588 4408);
DISPLAY 0.680851 (1588 4408);
PAINT GREEN (1588 4408);
FORCEPROP 2 LAST CDS_LIB standard
J 0
(1650 4400);
DISPLAY INVISIBLE (1650 4400);
FORCEPROP 1 LAST BODY_TYPE PLUMBING
J 0
(1650 4450);
DISPLAY 0.872340 (1650 4450);
PAINT GREEN (1650 4450);
DISPLAY INVISIBLE (1650 4450);
FORCEPROP 1 LAST HDL_TAP TRUE
J 0
(1975 4275);
DISPLAY 0.872340 (1975 4275);
DISPLAY INVISIBLE (1975 4275);
FORCEPROP 1 LAST PATH I164
J 0
(1648 4400);
DISPLAY 0.872340 (1648 4400);
PAINT GREEN (1648 4400);
DISPLAY INVISIBLE (1648 4400);
FORCEADD TAP..1
(1650 4300);
FORCEPROP 3 LASTPIN (1600 4300) SIG_NAME M_F_CPU0_SA_DQS_DP<8>
J 0
(1610 4310);
DISPLAY 0.659574 (1610 4310);
PAINT MONO (1610 4310);
DISPLAY INVISIBLE (1610 4310);
FORCEPROP 1 LASTPIN (1600 4300) BN 8
J 0
(1588 4308);
DISPLAY 0.680851 (1588 4308);
PAINT GREEN (1588 4308);
FORCEPROP 2 LAST CDS_LIB standard
J 0
(1650 4300);
DISPLAY INVISIBLE (1650 4300);
FORCEPROP 1 LAST BODY_TYPE PLUMBING
J 0
(1650 4350);
DISPLAY 0.872340 (1650 4350);
PAINT GREEN (1650 4350);
DISPLAY INVISIBLE (1650 4350);
FORCEPROP 1 LAST HDL_TAP TRUE
J 0
(1975 4175);
DISPLAY 0.872340 (1975 4175);
DISPLAY INVISIBLE (1975 4175);
FORCEPROP 1 LAST PATH I165
J 0
(1648 4300);
DISPLAY 0.872340 (1648 4300);
PAINT GREEN (1648 4300);
DISPLAY INVISIBLE (1648 4300);
FORCEADD TAP..1
(1825 4050);
FORCEPROP 3 LASTPIN (1775 4050) SIG_NAME M_F_CPU0_SA_DQS_DN<6>
J 0
(1785 4060);
DISPLAY 0.659574 (1785 4060);
PAINT MONO (1785 4060);
DISPLAY INVISIBLE (1785 4060);
FORCEPROP 1 LASTPIN (1775 4050) BN 6
J 0
(1763 4058);
DISPLAY 0.680851 (1763 4058);
PAINT GREEN (1763 4058);
FORCEPROP 2 LAST CDS_LIB standard
J 0
(1825 4050);
DISPLAY INVISIBLE (1825 4050);
FORCEPROP 1 LAST BODY_TYPE PLUMBING
J 0
(1825 4100);
DISPLAY 0.872340 (1825 4100);
PAINT GREEN (1825 4100);
DISPLAY INVISIBLE (1825 4100);
FORCEPROP 1 LAST HDL_TAP TRUE
J 0
(2150 3925);
DISPLAY 0.872340 (2150 3925);
DISPLAY INVISIBLE (2150 3925);
FORCEPROP 1 LAST PATH I166
J 0
(1823 4050);
DISPLAY 0.872340 (1823 4050);
PAINT GREEN (1823 4050);
DISPLAY INVISIBLE (1823 4050);
FORCEADD TAP..1
(1825 4150);
FORCEPROP 3 LASTPIN (1775 4150) SIG_NAME M_F_CPU0_SA_DQS_DN<7>
J 0
(1785 4160);
DISPLAY 0.659574 (1785 4160);
PAINT MONO (1785 4160);
DISPLAY INVISIBLE (1785 4160);
FORCEPROP 1 LASTPIN (1775 4150) BN 7
J 0
(1763 4158);
DISPLAY 0.680851 (1763 4158);
PAINT GREEN (1763 4158);
FORCEPROP 2 LAST CDS_LIB standard
J 0
(1825 4150);
DISPLAY INVISIBLE (1825 4150);
FORCEPROP 1 LAST BODY_TYPE PLUMBING
J 0
(1825 4200);
DISPLAY 0.872340 (1825 4200);
PAINT GREEN (1825 4200);
DISPLAY INVISIBLE (1825 4200);
FORCEPROP 1 LAST HDL_TAP TRUE
J 0
(2150 4025);
DISPLAY 0.872340 (2150 4025);
DISPLAY INVISIBLE (2150 4025);
FORCEPROP 1 LAST PATH I167
J 0
(1823 4150);
DISPLAY 0.872340 (1823 4150);
PAINT GREEN (1823 4150);
DISPLAY INVISIBLE (1823 4150);
FORCEADD TAP..1
(1825 4250);
FORCEPROP 3 LASTPIN (1775 4250) SIG_NAME M_F_CPU0_SA_DQS_DN<8>
J 0
(1785 4260);
DISPLAY 0.659574 (1785 4260);
PAINT MONO (1785 4260);
DISPLAY INVISIBLE (1785 4260);
FORCEPROP 1 LASTPIN (1775 4250) BN 8
J 0
(1763 4258);
DISPLAY 0.680851 (1763 4258);
PAINT GREEN (1763 4258);
FORCEPROP 2 LAST CDS_LIB standard
J 0
(1825 4250);
DISPLAY INVISIBLE (1825 4250);
FORCEPROP 1 LAST BODY_TYPE PLUMBING
J 0
(1825 4300);
DISPLAY 0.872340 (1825 4300);
PAINT GREEN (1825 4300);
DISPLAY INVISIBLE (1825 4300);
FORCEPROP 1 LAST HDL_TAP TRUE
J 0
(2150 4125);
DISPLAY 0.872340 (2150 4125);
DISPLAY INVISIBLE (2150 4125);
FORCEPROP 1 LAST PATH I168
J 0
(1823 4250);
DISPLAY 0.872340 (1823 4250);
PAINT GREEN (1823 4250);
DISPLAY INVISIBLE (1823 4250);
FORCEADD TAP..1
(1825 4350);
FORCEPROP 3 LASTPIN (1775 4350) SIG_NAME M_F_CPU0_SA_DQS_DN<9>
J 0
(1785 4360);
DISPLAY 0.659574 (1785 4360);
PAINT MONO (1785 4360);
DISPLAY INVISIBLE (1785 4360);
FORCEPROP 1 LASTPIN (1775 4350) BN 9
J 0
(1763 4358);
DISPLAY 0.680851 (1763 4358);
PAINT GREEN (1763 4358);
FORCEPROP 2 LAST CDS_LIB standard
J 0
(1825 4350);
DISPLAY INVISIBLE (1825 4350);
FORCEPROP 1 LAST BODY_TYPE PLUMBING
J 0
(1825 4400);
DISPLAY 0.872340 (1825 4400);
PAINT GREEN (1825 4400);
DISPLAY INVISIBLE (1825 4400);
FORCEPROP 1 LAST HDL_TAP TRUE
J 0
(2150 4225);
DISPLAY 0.872340 (2150 4225);
DISPLAY INVISIBLE (2150 4225);
FORCEPROP 1 LAST PATH I169
J 0
(1823 4350);
DISPLAY 0.872340 (1823 4350);
PAINT GREEN (1823 4350);
DISPLAY INVISIBLE (1823 4350);
FORCEADD OFFPAGE..1
(-3675 3300);
FORCEPROP 2 LAST $XR0 25 
J 0
(-3896 3300);
DISPLAY 0.638298 (-3896 3300);
PAINT MONO (-3896 3300);
FORCEPROP 2 LAST CDS_LIB standard
J 0
(-3675 3300);
PAINT MONO (-3675 3300);
DISPLAY INVISIBLE (-3675 3300);
FORCEPROP 1 LAST OFFPAGE TRUE
J 0
(-3350 3175);
DISPLAY 0.872340 (-3350 3175);
DISPLAY INVISIBLE (-3350 3175);
FORCEPROP 1 LAST COMMENT_BODY TRUE
J 0
(-3550 3200);
DISPLAY 0.872340 (-3550 3200);
PAINT GREEN (-3550 3200);
DISPLAY INVISIBLE (-3550 3200);
FORCEPROP 2 LAST PATH I17
J 0
(-3625 3375);
DISPLAY 1.021277 (-3625 3375);
DISPLAY INVISIBLE (-3625 3375);
FORCEADD OFFPAGE..2
(2775 3325);
FORCEPROP 2 LAST $XR1 93 
J 0
(3054 3325);
DISPLAY 0.638298 (3054 3325);
PAINT MONO (3054 3325);
FORCEPROP 2 LAST $XR0 25 
J 0
(2964 3325);
DISPLAY 0.638298 (2964 3325);
PAINT MONO (2964 3325);
FORCEPROP 2 LAST CDS_LIB standard
J 0
(2775 3325);
PAINT MONO (2775 3325);
DISPLAY INVISIBLE (2775 3325);
FORCEPROP 1 LAST OFFPAGE TRUE
J 0
(3100 3200);
DISPLAY 1.170213 (3100 3200);
PAINT GREEN (3100 3200);
DISPLAY INVISIBLE (3100 3200);
FORCEPROP 1 LAST COMMENT_BODY TRUE
J 0
(2730 3230);
DISPLAY 1.170213 (2730 3230);
PAINT GREEN (2730 3230);
DISPLAY INVISIBLE (2730 3230);
FORCEPROP 2 LAST PATH I170
J 0
(2950 3400);
DISPLAY 1.021277 (2950 3400);
DISPLAY INVISIBLE (2950 3400);
FORCEADD OFFPAGE..2
(2775 3375);
FORCEPROP 2 LAST $XR1 93 
J 0
(3054 3375);
DISPLAY 0.638298 (3054 3375);
PAINT MONO (3054 3375);
FORCEPROP 2 LAST $XR0 25 
J 0
(2964 3375);
DISPLAY 0.638298 (2964 3375);
PAINT MONO (2964 3375);
FORCEPROP 2 LAST CDS_LIB standard
J 0
(2775 3375);
PAINT MONO (2775 3375);
DISPLAY INVISIBLE (2775 3375);
FORCEPROP 1 LAST OFFPAGE TRUE
J 0
(3100 3250);
DISPLAY 1.170213 (3100 3250);
PAINT GREEN (3100 3250);
DISPLAY INVISIBLE (3100 3250);
FORCEPROP 1 LAST COMMENT_BODY TRUE
J 0
(2730 3280);
DISPLAY 1.170213 (2730 3280);
PAINT GREEN (2730 3280);
DISPLAY INVISIBLE (2730 3280);
FORCEPROP 2 LAST PATH I171
J 0
(2950 3450);
DISPLAY 1.021277 (2950 3450);
DISPLAY INVISIBLE (2950 3450);
FORCEADD OFFPAGE..2
(2775 4425);
FORCEPROP 2 LAST $XR1 93 
J 0
(3054 4425);
DISPLAY 0.638298 (3054 4425);
PAINT MONO (3054 4425);
FORCEPROP 2 LAST $XR0 25 
J 0
(2964 4425);
DISPLAY 0.638298 (2964 4425);
PAINT MONO (2964 4425);
FORCEPROP 2 LAST CDS_LIB standard
J 0
(2775 4425);
PAINT MONO (2775 4425);
DISPLAY INVISIBLE (2775 4425);
FORCEPROP 1 LAST OFFPAGE TRUE
J 0
(3100 4300);
DISPLAY 1.170213 (3100 4300);
PAINT GREEN (3100 4300);
DISPLAY INVISIBLE (3100 4300);
FORCEPROP 1 LAST COMMENT_BODY TRUE
J 0
(2730 4330);
DISPLAY 1.170213 (2730 4330);
PAINT GREEN (2730 4330);
DISPLAY INVISIBLE (2730 4330);
FORCEPROP 2 LAST PATH I172
J 0
(2950 4500);
DISPLAY 1.021277 (2950 4500);
DISPLAY INVISIBLE (2950 4500);
FORCEADD OFFPAGE..2
(2775 4375);
FORCEPROP 2 LAST $XR1 93 
J 0
(3054 4375);
DISPLAY 0.638298 (3054 4375);
PAINT MONO (3054 4375);
FORCEPROP 2 LAST $XR0 25 
J 0
(2964 4375);
DISPLAY 0.638298 (2964 4375);
PAINT MONO (2964 4375);
FORCEPROP 2 LAST CDS_LIB standard
J 0
(2775 4375);
PAINT MONO (2775 4375);
DISPLAY INVISIBLE (2775 4375);
FORCEPROP 1 LAST OFFPAGE TRUE
J 0
(3100 4250);
DISPLAY 1.170213 (3100 4250);
PAINT GREEN (3100 4250);
DISPLAY INVISIBLE (3100 4250);
FORCEPROP 1 LAST COMMENT_BODY TRUE
J 0
(2730 4280);
DISPLAY 1.170213 (2730 4280);
PAINT GREEN (2730 4280);
DISPLAY INVISIBLE (2730 4280);
FORCEPROP 2 LAST PATH I173
J 0
(2950 4450);
DISPLAY 1.021277 (2950 4450);
DISPLAY INVISIBLE (2950 4450);
FORCEADD UNIVERSAL_GND..1
(3325 700);
FORCEPROP 3 LASTPIN (3325 750) SIG_NAME GND\g
J 0
(3335 760);
DISPLAY 0.659574 (3335 760);
PAINT MONO (3335 760);
DISPLAY INVISIBLE (3335 760);
FORCEPROP 2 LAST CDS_LIB logical_power
J 0
(3325 700);
PAINT MONO (3325 700);
DISPLAY INVISIBLE (3325 700);
FORCEPROP 1 LAST HDL_POWER GND
J 1
(3350 625);
DISPLAY 0.872340 (3350 625);
PAINT GREEN (3350 625);
DISPLAY INVISIBLE (3350 625);
FORCEPROP 1 LAST PATH I174
J 0
(3400 700);
DISPLAY 0.872340 (3400 700);
PAINT AQUA (3400 700);
DISPLAY INVISIBLE (3400 700);
FORCEADD SCONN288_ADR50017P130CC..3
(4175 2775);
FORCEPROP 1 LAST PART_NUMBER DFHST8FS461
J 0
(3720 4699);
DISPLAY 0.723404 (3720 4699);
PAINT GREEN (3720 4699);
DISPLAY INVISIBLE (3720 4699);
FORCEPROP 2 LAST VALUE SCONN288_ADR50017-P130CC
J 0
(3725 4800);
DISPLAY 1.021277 (3725 4800);
FORCEPROP 1 LAST MATERIAL IO
J 0
(3720 4572);
DISPLAY 0.723404 (3720 4572);
PAINT GREEN (3720 4572);
FORCEPROP 2 LAST PART_TYPE SMLF
J 0
(3725 4850);
DISPLAY 1.021277 (3725 4850);
FORCEPROP 1 LAST $LOCATION J11
J 0
(3725 4750);
DISPLAY 0.723404 (3725 4750);
PAINT GREEN (3725 4750);
FORCEPROP 0 LASTPIN (4775 1150) $PN G1
J 0
(4785 1160);
DISPLAY 0.680851 (4785 1160);
PAINT MONO (4785 1160);
FORCEPROP 0 LASTPIN (4775 1100) $PN G2
J 0
(4785 1110);
DISPLAY 0.680851 (4785 1110);
PAINT MONO (4785 1110);
FORCEPROP 0 LASTPIN (4775 1050) $PN G3
J 0
(4785 1060);
DISPLAY 0.680851 (4785 1060);
PAINT MONO (4785 1060);
FORCEPROP 0 LASTPIN (3575 4300) $PN 1
J 2
(3565 4310);
DISPLAY 0.680851 (3565 4310);
PAINT MONO (3565 4310);
FORCEPROP 0 LASTPIN (3575 4350) $PN 145
J 2
(3565 4360);
DISPLAY 0.680851 (3565 4360);
PAINT MONO (3565 4360);
FORCEPROP 0 LASTPIN (3575 4400) $PN 146
J 2
(3565 4410);
DISPLAY 0.680851 (3565 4410);
PAINT MONO (3565 4410);
FORCEPROP 0 LASTPIN (4775 1250) $PN 6
J 0
(4785 1260);
DISPLAY 0.680851 (4785 1260);
PAINT MONO (4785 1260);
FORCEPROP 0 LASTPIN (4775 1300) $PN 8
J 0
(4785 1310);
DISPLAY 0.680851 (4785 1310);
PAINT MONO (4785 1310);
FORCEPROP 0 LASTPIN (4775 1350) $PN 10
J 0
(4785 1360);
DISPLAY 0.680851 (4785 1360);
PAINT MONO (4785 1360);
FORCEPROP 0 LASTPIN (4775 1400) $PN 13
J 0
(4785 1410);
DISPLAY 0.680851 (4785 1410);
PAINT MONO (4785 1410);
FORCEPROP 0 LASTPIN (4775 1450) $PN 15
J 0
(4785 1460);
DISPLAY 0.680851 (4785 1460);
PAINT MONO (4785 1460);
FORCEPROP 0 LASTPIN (4775 1500) $PN 17
J 0
(4785 1510);
DISPLAY 0.680851 (4785 1510);
PAINT MONO (4785 1510);
FORCEPROP 0 LASTPIN (4775 1550) $PN 19
J 0
(4785 1560);
DISPLAY 0.680851 (4785 1560);
PAINT MONO (4785 1560);
FORCEPROP 0 LASTPIN (4775 1600) $PN 21
J 0
(4785 1610);
DISPLAY 0.680851 (4785 1610);
PAINT MONO (4785 1610);
FORCEPROP 0 LASTPIN (4775 1650) $PN 24
J 0
(4785 1660);
DISPLAY 0.680851 (4785 1660);
PAINT MONO (4785 1660);
FORCEPROP 0 LASTPIN (4775 1700) $PN 26
J 0
(4785 1710);
DISPLAY 0.680851 (4785 1710);
PAINT MONO (4785 1710);
FORCEPROP 0 LASTPIN (4775 1750) $PN 28
J 0
(4785 1760);
DISPLAY 0.680851 (4785 1760);
PAINT MONO (4785 1760);
FORCEPROP 0 LASTPIN (4775 1800) $PN 30
J 0
(4785 1810);
DISPLAY 0.680851 (4785 1810);
PAINT MONO (4785 1810);
FORCEPROP 0 LASTPIN (4775 1850) $PN 32
J 0
(4785 1860);
DISPLAY 0.680851 (4785 1860);
PAINT MONO (4785 1860);
FORCEPROP 0 LASTPIN (4775 1900) $PN 35
J 0
(4785 1910);
DISPLAY 0.680851 (4785 1910);
PAINT MONO (4785 1910);
FORCEPROP 0 LASTPIN (4775 1950) $PN 37
J 0
(4785 1960);
DISPLAY 0.680851 (4785 1960);
PAINT MONO (4785 1960);
FORCEPROP 0 LASTPIN (4775 2000) $PN 39
J 0
(4785 2010);
DISPLAY 0.680851 (4785 2010);
PAINT MONO (4785 2010);
FORCEPROP 0 LASTPIN (4775 2050) $PN 41
J 0
(4785 2060);
DISPLAY 0.680851 (4785 2060);
PAINT MONO (4785 2060);
FORCEPROP 0 LASTPIN (4775 2100) $PN 43
J 0
(4785 2110);
DISPLAY 0.680851 (4785 2110);
PAINT MONO (4785 2110);
FORCEPROP 0 LASTPIN (4775 2150) $PN 46
J 0
(4785 2160);
DISPLAY 0.680851 (4785 2160);
PAINT MONO (4785 2160);
FORCEPROP 0 LASTPIN (4775 2200) $PN 48
J 0
(4785 2210);
DISPLAY 0.680851 (4785 2210);
PAINT MONO (4785 2210);
FORCEPROP 0 LASTPIN (4775 2250) $PN 50
J 0
(4785 2260);
DISPLAY 0.680851 (4785 2260);
PAINT MONO (4785 2260);
FORCEPROP 0 LASTPIN (4775 2300) $PN 52
J 0
(4785 2310);
DISPLAY 0.680851 (4785 2310);
PAINT MONO (4785 2310);
FORCEPROP 0 LASTPIN (4775 2350) $PN 54
J 0
(4785 2360);
DISPLAY 0.680851 (4785 2360);
PAINT MONO (4785 2360);
FORCEPROP 0 LASTPIN (4775 2400) $PN 57
J 0
(4785 2410);
DISPLAY 0.680851 (4785 2410);
PAINT MONO (4785 2410);
FORCEPROP 0 LASTPIN (4775 2450) $PN 59
J 0
(4785 2460);
DISPLAY 0.680851 (4785 2460);
PAINT MONO (4785 2460);
FORCEPROP 0 LASTPIN (4775 2500) $PN 61
J 0
(4785 2510);
DISPLAY 0.680851 (4785 2510);
PAINT MONO (4785 2510);
FORCEPROP 0 LASTPIN (4775 2550) $PN 63
J 0
(4785 2560);
DISPLAY 0.680851 (4785 2560);
PAINT MONO (4785 2560);
FORCEPROP 0 LASTPIN (4775 2600) $PN 65
J 0
(4785 2610);
DISPLAY 0.680851 (4785 2610);
PAINT MONO (4785 2610);
FORCEPROP 0 LASTPIN (4775 2650) $PN 67
J 0
(4785 2660);
DISPLAY 0.680851 (4785 2660);
PAINT MONO (4785 2660);
FORCEPROP 0 LASTPIN (4775 2700) $PN 69
J 0
(4785 2710);
DISPLAY 0.680851 (4785 2710);
PAINT MONO (4785 2710);
FORCEPROP 0 LASTPIN (4775 2750) $PN 71
J 0
(4785 2760);
DISPLAY 0.680851 (4785 2760);
PAINT MONO (4785 2760);
FORCEPROP 0 LASTPIN (4775 2800) $PN 73
J 0
(4785 2810);
DISPLAY 0.680851 (4785 2810);
PAINT MONO (4785 2810);
FORCEPROP 0 LASTPIN (4775 2850) $PN 75
J 0
(4785 2860);
DISPLAY 0.680851 (4785 2860);
PAINT MONO (4785 2860);
FORCEPROP 0 LASTPIN (4775 2900) $PN 77
J 0
(4785 2910);
DISPLAY 0.680851 (4785 2910);
PAINT MONO (4785 2910);
FORCEPROP 0 LASTPIN (4775 2950) $PN 79
J 0
(4785 2960);
DISPLAY 0.680851 (4785 2960);
PAINT MONO (4785 2960);
FORCEPROP 0 LASTPIN (4775 3000) $PN 81
J 0
(4785 3010);
DISPLAY 0.680851 (4785 3010);
PAINT MONO (4785 3010);
FORCEPROP 0 LASTPIN (4775 3050) $PN 83
J 0
(4785 3060);
DISPLAY 0.680851 (4785 3060);
PAINT MONO (4785 3060);
FORCEPROP 0 LASTPIN (4775 3100) $PN 85
J 0
(4785 3110);
DISPLAY 0.680851 (4785 3110);
PAINT MONO (4785 3110);
FORCEPROP 0 LASTPIN (4775 3150) $PN 88
J 0
(4785 3160);
DISPLAY 0.680851 (4785 3160);
PAINT MONO (4785 3160);
FORCEPROP 0 LASTPIN (4775 3200) $PN 90
J 0
(4785 3210);
DISPLAY 0.680851 (4785 3210);
PAINT MONO (4785 3210);
FORCEPROP 0 LASTPIN (4775 3250) $PN 92
J 0
(4785 3260);
DISPLAY 0.680851 (4785 3260);
PAINT MONO (4785 3260);
FORCEPROP 0 LASTPIN (4775 3300) $PN 95
J 0
(4785 3310);
DISPLAY 0.680851 (4785 3310);
PAINT MONO (4785 3310);
FORCEPROP 0 LASTPIN (4775 3350) $PN 97
J 0
(4785 3360);
DISPLAY 0.680851 (4785 3360);
PAINT MONO (4785 3360);
FORCEPROP 0 LASTPIN (4775 3400) $PN 99
J 0
(4785 3410);
DISPLAY 0.680851 (4785 3410);
PAINT MONO (4785 3410);
FORCEPROP 0 LASTPIN (4775 3450) $PN 101
J 0
(4785 3460);
DISPLAY 0.680851 (4785 3460);
PAINT MONO (4785 3460);
FORCEPROP 0 LASTPIN (4775 3500) $PN 103
J 0
(4785 3510);
DISPLAY 0.680851 (4785 3510);
PAINT MONO (4785 3510);
FORCEPROP 0 LASTPIN (4775 3550) $PN 106
J 0
(4785 3560);
DISPLAY 0.680851 (4785 3560);
PAINT MONO (4785 3560);
FORCEPROP 0 LASTPIN (4775 3600) $PN 108
J 0
(4785 3610);
DISPLAY 0.680851 (4785 3610);
PAINT MONO (4785 3610);
FORCEPROP 0 LASTPIN (4775 3650) $PN 110
J 0
(4785 3660);
DISPLAY 0.680851 (4785 3660);
PAINT MONO (4785 3660);
FORCEPROP 0 LASTPIN (4775 3700) $PN 112
J 0
(4785 3710);
DISPLAY 0.680851 (4785 3710);
PAINT MONO (4785 3710);
FORCEPROP 0 LASTPIN (4775 3750) $PN 114
J 0
(4785 3760);
DISPLAY 0.680851 (4785 3760);
PAINT MONO (4785 3760);
FORCEPROP 0 LASTPIN (4775 3800) $PN 117
J 0
(4785 3810);
DISPLAY 0.680851 (4785 3810);
PAINT MONO (4785 3810);
FORCEPROP 0 LASTPIN (4775 3850) $PN 119
J 0
(4785 3860);
DISPLAY 0.680851 (4785 3860);
PAINT MONO (4785 3860);
FORCEPROP 0 LASTPIN (4775 3900) $PN 121
J 0
(4785 3910);
DISPLAY 0.680851 (4785 3910);
PAINT MONO (4785 3910);
FORCEPROP 0 LASTPIN (4775 3950) $PN 123
J 0
(4785 3960);
DISPLAY 0.680851 (4785 3960);
PAINT MONO (4785 3960);
FORCEPROP 0 LASTPIN (4775 4000) $PN 125
J 0
(4785 4010);
DISPLAY 0.680851 (4785 4010);
PAINT MONO (4785 4010);
FORCEPROP 0 LASTPIN (4775 4050) $PN 128
J 0
(4785 4060);
DISPLAY 0.680851 (4785 4060);
PAINT MONO (4785 4060);
FORCEPROP 0 LASTPIN (4775 4100) $PN 130
J 0
(4785 4110);
DISPLAY 0.680851 (4785 4110);
PAINT MONO (4785 4110);
FORCEPROP 0 LASTPIN (4775 4150) $PN 132
J 0
(4785 4160);
DISPLAY 0.680851 (4785 4160);
PAINT MONO (4785 4160);
FORCEPROP 0 LASTPIN (4775 4200) $PN 134
J 0
(4785 4210);
DISPLAY 0.680851 (4785 4210);
PAINT MONO (4785 4210);
FORCEPROP 0 LASTPIN (4775 4250) $PN 136
J 0
(4785 4260);
DISPLAY 0.680851 (4785 4260);
PAINT MONO (4785 4260);
FORCEPROP 0 LASTPIN (4775 4300) $PN 139
J 0
(4785 4310);
DISPLAY 0.680851 (4785 4310);
PAINT MONO (4785 4310);
FORCEPROP 0 LASTPIN (4775 4350) $PN 141
J 0
(4785 4360);
DISPLAY 0.680851 (4785 4360);
PAINT MONO (4785 4360);
FORCEPROP 0 LASTPIN (4775 4400) $PN 143
J 0
(4785 4410);
DISPLAY 0.680851 (4785 4410);
PAINT MONO (4785 4410);
FORCEPROP 0 LASTPIN (3575 1150) $PN 151
J 2
(3565 1160);
DISPLAY 0.680851 (3565 1160);
PAINT MONO (3565 1160);
FORCEPROP 0 LASTPIN (3575 1200) $PN 153
J 2
(3565 1210);
DISPLAY 0.680851 (3565 1210);
PAINT MONO (3565 1210);
FORCEPROP 0 LASTPIN (3575 1250) $PN 155
J 2
(3565 1260);
DISPLAY 0.680851 (3565 1260);
PAINT MONO (3565 1260);
FORCEPROP 0 LASTPIN (3575 1300) $PN 158
J 2
(3565 1310);
DISPLAY 0.680851 (3565 1310);
PAINT MONO (3565 1310);
FORCEPROP 0 LASTPIN (3575 1350) $PN 160
J 2
(3565 1360);
DISPLAY 0.680851 (3565 1360);
PAINT MONO (3565 1360);
FORCEPROP 0 LASTPIN (3575 1400) $PN 162
J 2
(3565 1410);
DISPLAY 0.680851 (3565 1410);
PAINT MONO (3565 1410);
FORCEPROP 0 LASTPIN (3575 1450) $PN 164
J 2
(3565 1460);
DISPLAY 0.680851 (3565 1460);
PAINT MONO (3565 1460);
FORCEPROP 0 LASTPIN (3575 1500) $PN 166
J 2
(3565 1510);
DISPLAY 0.680851 (3565 1510);
PAINT MONO (3565 1510);
FORCEPROP 0 LASTPIN (3575 1550) $PN 169
J 2
(3565 1560);
DISPLAY 0.680851 (3565 1560);
PAINT MONO (3565 1560);
FORCEPROP 0 LASTPIN (3575 1600) $PN 171
J 2
(3565 1610);
DISPLAY 0.680851 (3565 1610);
PAINT MONO (3565 1610);
FORCEPROP 0 LASTPIN (3575 1650) $PN 173
J 2
(3565 1660);
DISPLAY 0.680851 (3565 1660);
PAINT MONO (3565 1660);
FORCEPROP 0 LASTPIN (3575 1700) $PN 175
J 2
(3565 1710);
DISPLAY 0.680851 (3565 1710);
PAINT MONO (3565 1710);
FORCEPROP 0 LASTPIN (3575 1750) $PN 177
J 2
(3565 1760);
DISPLAY 0.680851 (3565 1760);
PAINT MONO (3565 1760);
FORCEPROP 0 LASTPIN (3575 1800) $PN 180
J 2
(3565 1810);
DISPLAY 0.680851 (3565 1810);
PAINT MONO (3565 1810);
FORCEPROP 0 LASTPIN (3575 1850) $PN 182
J 2
(3565 1860);
DISPLAY 0.680851 (3565 1860);
PAINT MONO (3565 1860);
FORCEPROP 0 LASTPIN (3575 1900) $PN 184
J 2
(3565 1910);
DISPLAY 0.680851 (3565 1910);
PAINT MONO (3565 1910);
FORCEPROP 0 LASTPIN (3575 1950) $PN 186
J 2
(3565 1960);
DISPLAY 0.680851 (3565 1960);
PAINT MONO (3565 1960);
FORCEPROP 0 LASTPIN (3575 2000) $PN 188
J 2
(3565 2010);
DISPLAY 0.680851 (3565 2010);
PAINT MONO (3565 2010);
FORCEPROP 0 LASTPIN (3575 2050) $PN 191
J 2
(3565 2060);
DISPLAY 0.680851 (3565 2060);
PAINT MONO (3565 2060);
FORCEPROP 0 LASTPIN (3575 2100) $PN 193
J 2
(3565 2110);
DISPLAY 0.680851 (3565 2110);
PAINT MONO (3565 2110);
FORCEPROP 0 LASTPIN (3575 2150) $PN 195
J 2
(3565 2160);
DISPLAY 0.680851 (3565 2160);
PAINT MONO (3565 2160);
FORCEPROP 0 LASTPIN (3575 2200) $PN 197
J 2
(3565 2210);
DISPLAY 0.680851 (3565 2210);
PAINT MONO (3565 2210);
FORCEPROP 0 LASTPIN (3575 2250) $PN 199
J 2
(3565 2260);
DISPLAY 0.680851 (3565 2260);
PAINT MONO (3565 2260);
FORCEPROP 0 LASTPIN (3575 2300) $PN 202
J 2
(3565 2310);
DISPLAY 0.680851 (3565 2310);
PAINT MONO (3565 2310);
FORCEPROP 0 LASTPIN (3575 2350) $PN 204
J 2
(3565 2360);
DISPLAY 0.680851 (3565 2360);
PAINT MONO (3565 2360);
FORCEPROP 0 LASTPIN (3575 2400) $PN 206
J 2
(3565 2410);
DISPLAY 0.680851 (3565 2410);
PAINT MONO (3565 2410);
FORCEPROP 0 LASTPIN (3575 2450) $PN 208
J 2
(3565 2460);
DISPLAY 0.680851 (3565 2460);
PAINT MONO (3565 2460);
FORCEPROP 0 LASTPIN (3575 2500) $PN 210
J 2
(3565 2510);
DISPLAY 0.680851 (3565 2510);
PAINT MONO (3565 2510);
FORCEPROP 0 LASTPIN (3575 2550) $PN 212
J 2
(3565 2560);
DISPLAY 0.680851 (3565 2560);
PAINT MONO (3565 2560);
FORCEPROP 0 LASTPIN (3575 2600) $PN 214
J 2
(3565 2610);
DISPLAY 0.680851 (3565 2610);
PAINT MONO (3565 2610);
FORCEPROP 0 LASTPIN (3575 2650) $PN 216
J 2
(3565 2660);
DISPLAY 0.680851 (3565 2660);
PAINT MONO (3565 2660);
FORCEPROP 0 LASTPIN (3575 2700) $PN 219
J 2
(3565 2710);
DISPLAY 0.680851 (3565 2710);
PAINT MONO (3565 2710);
FORCEPROP 0 LASTPIN (3575 2750) $PN 222
J 2
(3565 2760);
DISPLAY 0.680851 (3565 2760);
PAINT MONO (3565 2760);
FORCEPROP 0 LASTPIN (3575 2800) $PN 224
J 2
(3565 2810);
DISPLAY 0.680851 (3565 2810);
PAINT MONO (3565 2810);
FORCEPROP 0 LASTPIN (3575 2850) $PN 226
J 2
(3565 2860);
DISPLAY 0.680851 (3565 2860);
PAINT MONO (3565 2860);
FORCEPROP 0 LASTPIN (3575 2900) $PN 228
J 2
(3565 2910);
DISPLAY 0.680851 (3565 2910);
PAINT MONO (3565 2910);
FORCEPROP 0 LASTPIN (3575 2950) $PN 230
J 2
(3565 2960);
DISPLAY 0.680851 (3565 2960);
PAINT MONO (3565 2960);
FORCEPROP 0 LASTPIN (3575 3000) $PN 233
J 2
(3565 3010);
DISPLAY 0.680851 (3565 3010);
PAINT MONO (3565 3010);
FORCEPROP 0 LASTPIN (3575 3050) $PN 235
J 2
(3565 3060);
DISPLAY 0.680851 (3565 3060);
PAINT MONO (3565 3060);
FORCEPROP 0 LASTPIN (3575 3100) $PN 237
J 2
(3565 3110);
DISPLAY 0.680851 (3565 3110);
PAINT MONO (3565 3110);
FORCEPROP 0 LASTPIN (3575 3150) $PN 240
J 2
(3565 3160);
DISPLAY 0.680851 (3565 3160);
PAINT MONO (3565 3160);
FORCEPROP 0 LASTPIN (3575 3200) $PN 242
J 2
(3565 3210);
DISPLAY 0.680851 (3565 3210);
PAINT MONO (3565 3210);
FORCEPROP 0 LASTPIN (3575 3250) $PN 244
J 2
(3565 3260);
DISPLAY 0.680851 (3565 3260);
PAINT MONO (3565 3260);
FORCEPROP 0 LASTPIN (3575 3300) $PN 246
J 2
(3565 3310);
DISPLAY 0.680851 (3565 3310);
PAINT MONO (3565 3310);
FORCEPROP 0 LASTPIN (3575 3350) $PN 248
J 2
(3565 3360);
DISPLAY 0.680851 (3565 3360);
PAINT MONO (3565 3360);
FORCEPROP 0 LASTPIN (3575 3400) $PN 251
J 2
(3565 3410);
DISPLAY 0.680851 (3565 3410);
PAINT MONO (3565 3410);
FORCEPROP 0 LASTPIN (3575 3450) $PN 253
J 2
(3565 3460);
DISPLAY 0.680851 (3565 3460);
PAINT MONO (3565 3460);
FORCEPROP 0 LASTPIN (3575 3500) $PN 255
J 2
(3565 3510);
DISPLAY 0.680851 (3565 3510);
PAINT MONO (3565 3510);
FORCEPROP 0 LASTPIN (3575 3550) $PN 257
J 2
(3565 3560);
DISPLAY 0.680851 (3565 3560);
PAINT MONO (3565 3560);
FORCEPROP 0 LASTPIN (3575 3600) $PN 259
J 2
(3565 3610);
DISPLAY 0.680851 (3565 3610);
PAINT MONO (3565 3610);
FORCEPROP 0 LASTPIN (3575 3650) $PN 262
J 2
(3565 3660);
DISPLAY 0.680851 (3565 3660);
PAINT MONO (3565 3660);
FORCEPROP 0 LASTPIN (3575 3700) $PN 264
J 2
(3565 3710);
DISPLAY 0.680851 (3565 3710);
PAINT MONO (3565 3710);
FORCEPROP 0 LASTPIN (3575 3750) $PN 266
J 2
(3565 3760);
DISPLAY 0.680851 (3565 3760);
PAINT MONO (3565 3760);
FORCEPROP 0 LASTPIN (3575 3800) $PN 268
J 2
(3565 3810);
DISPLAY 0.680851 (3565 3810);
PAINT MONO (3565 3810);
FORCEPROP 0 LASTPIN (3575 3850) $PN 270
J 2
(3565 3860);
DISPLAY 0.680851 (3565 3860);
PAINT MONO (3565 3860);
FORCEPROP 0 LASTPIN (3575 3900) $PN 273
J 2
(3565 3910);
DISPLAY 0.680851 (3565 3910);
PAINT MONO (3565 3910);
FORCEPROP 0 LASTPIN (3575 3950) $PN 275
J 2
(3565 3960);
DISPLAY 0.680851 (3565 3960);
PAINT MONO (3565 3960);
FORCEPROP 0 LASTPIN (3575 4000) $PN 277
J 2
(3565 4010);
DISPLAY 0.680851 (3565 4010);
PAINT MONO (3565 4010);
FORCEPROP 0 LASTPIN (3575 4050) $PN 279
J 2
(3565 4060);
DISPLAY 0.680851 (3565 4060);
PAINT MONO (3565 4060);
FORCEPROP 0 LASTPIN (3575 4100) $PN 281
J 2
(3565 4110);
DISPLAY 0.680851 (3565 4110);
PAINT MONO (3565 4110);
FORCEPROP 0 LASTPIN (3575 4150) $PN 284
J 2
(3565 4160);
DISPLAY 0.680851 (3565 4160);
PAINT MONO (3565 4160);
FORCEPROP 0 LASTPIN (3575 4200) $PN 286
J 2
(3565 4210);
DISPLAY 0.680851 (3565 4210);
PAINT MONO (3565 4210);
FORCEPROP 0 LASTPIN (3575 4250) $PN 288
J 2
(3565 4260);
DISPLAY 0.680851 (3565 4260);
PAINT MONO (3565 4260);
FORCEPROP 1 LAST NEEDS_NO_SIZE TRUE
J 0
(4175 2775);
DISPLAY 0.723404 (4175 2775);
PAINT GREEN (4175 2775);
DISPLAY INVISIBLE (4175 2775);
FORCEPROP 1 LAST CDS_LMAN_SYM_OUTLINE -450,1775,450,-1775
J 0
(4175 2775);
DISPLAY 0.468085 (4175 2775);
PAINT GREEN (4175 2775);
DISPLAY INVISIBLE (4175 2775);
FORCEPROP 2 LAST CDS_LIB pure_quanta
J 0
(4175 2775);
DISPLAY INVISIBLE (4175 2775);
FORCEPROP 2 LAST CDS_LOCATION J11
J 0
(3725 4900);
DISPLAY 1.021277 (3725 4900);
DISPLAY INVISIBLE (3725 4900);
FORCEPROP 0 LAST $SEC 3
J 0
(3725 4900);
DISPLAY 0.680851 (3725 4900);
PAINT MONO (3725 4900);
DISPLAY INVISIBLE (3725 4900);
FORCEPROP 2 LAST CDS_SEC 3
J 0
(3725 4900);
DISPLAY 1.021277 (3725 4900);
DISPLAY INVISIBLE (3725 4900);
FORCEPROP 1 LAST PATH I175
J 0
(4175 2775);
DISPLAY 0.723404 (4175 2775);
PAINT GREEN (4175 2775);
DISPLAY INVISIBLE (4175 2775);
FORCEADD UNIVERSAL_GND..1
(5025 700);
FORCEPROP 3 LASTPIN (5025 750) SIG_NAME GND\g
J 0
(5035 760);
DISPLAY 0.659574 (5035 760);
PAINT MONO (5035 760);
DISPLAY INVISIBLE (5035 760);
FORCEPROP 2 LAST CDS_LIB logical_power
J 0
(5025 700);
PAINT MONO (5025 700);
DISPLAY INVISIBLE (5025 700);
FORCEPROP 1 LAST HDL_POWER GND
J 1
(5050 625);
DISPLAY 0.872340 (5050 625);
PAINT GREEN (5050 625);
DISPLAY INVISIBLE (5050 625);
FORCEPROP 1 LAST PATH I176
J 0
(5100 700);
DISPLAY 0.872340 (5100 700);
PAINT AQUA (5100 700);
DISPLAY INVISIBLE (5100 700);
FORCEADD VCC_CORE..1
(3325 4950);
FORCEPROP 3 LASTPIN (3325 4900) SIG_NAME P12V_S3_AUX_CPU0_NVDIMM\g
J 0
(3335 4910);
DISPLAY 0.659574 (3335 4910);
PAINT MONO (3335 4910);
DISPLAY INVISIBLE (3335 4910);
FORCEPROP 1 LAST HDL_POWER P12V_S3_AUX_CPU0_NVDIMM
J 1
(3325 5000);
DISPLAY 1.148936 (3325 5000);
PAINT GREEN (3325 5000);
FORCEPROP 2 LAST CDS_LIB logical_power
J 0
(3325 4950);
PAINT MONO (3325 4950);
DISPLAY INVISIBLE (3325 4950);
FORCEPROP 1 LAST PATH I177
J 0
(3375 4975);
DISPLAY 0.872340 (3375 4975);
PAINT AQUA (3375 4975);
DISPLAY INVISIBLE (3375 4975);
FORCEADD SCONN288_ADR50017P130CC..2
(750 3400);
FORCEPROP 1 LAST PART_NUMBER DFHST8FS461
J 0
(157 4700);
DISPLAY 0.723404 (157 4700);
PAINT GREEN (157 4700);
DISPLAY INVISIBLE (157 4700);
FORCEPROP 1 LAST MATERIAL IO
J 0
(157 4573);
DISPLAY 0.723404 (157 4573);
PAINT GREEN (157 4573);
FORCEPROP 2 LAST VALUE SCONN288_ADR50017-P130CC
J 0
(168 4803);
DISPLAY 1.021277 (168 4803);
FORCEPROP 2 LAST PART_TYPE SMLF
J 0
(168 4853);
DISPLAY 1.021277 (168 4853);
FORCEPROP 1 LAST LOCATION J11
J 0
(150 4750);
DISPLAY 0.723404 (150 4750);
PAINT GREEN (150 4750);
FORCEPROP 0 LASTPIN (1500 3450) $PN 12
J 0
(1510 3460);
DISPLAY 0.680851 (1510 3460);
PAINT MONO (1510 3460);
FORCEPROP 0 LASTPIN (1500 3500) $PN 11
J 0
(1510 3510);
DISPLAY 0.680851 (1510 3510);
PAINT MONO (1510 3510);
FORCEPROP 0 LASTPIN (1500 2400) $PN 105
J 0
(1510 2410);
DISPLAY 0.680851 (1510 2410);
PAINT MONO (1510 2410);
FORCEPROP 0 LASTPIN (1500 2450) $PN 104
J 0
(1510 2460);
DISPLAY 0.680851 (1510 2460);
PAINT MONO (1510 2460);
FORCEPROP 0 LASTPIN (1500 3550) $PN 23
J 0
(1510 3560);
DISPLAY 0.680851 (1510 3560);
PAINT MONO (1510 3560);
FORCEPROP 0 LASTPIN (1500 3600) $PN 22
J 0
(1510 3610);
DISPLAY 0.680851 (1510 3610);
PAINT MONO (1510 3610);
FORCEPROP 0 LASTPIN (1500 2500) $PN 116
J 0
(1510 2510);
DISPLAY 0.680851 (1510 2510);
PAINT MONO (1510 2510);
FORCEPROP 0 LASTPIN (1500 2550) $PN 115
J 0
(1510 2560);
DISPLAY 0.680851 (1510 2560);
PAINT MONO (1510 2560);
FORCEPROP 0 LASTPIN (1500 3650) $PN 34
J 0
(1510 3660);
DISPLAY 0.680851 (1510 3660);
PAINT MONO (1510 3660);
FORCEPROP 0 LASTPIN (1500 3700) $PN 33
J 0
(1510 3710);
DISPLAY 0.680851 (1510 3710);
PAINT MONO (1510 3710);
FORCEPROP 0 LASTPIN (1500 2600) $PN 127
J 0
(1510 2610);
DISPLAY 0.680851 (1510 2610);
PAINT MONO (1510 2610);
FORCEPROP 0 LASTPIN (1500 2650) $PN 126
J 0
(1510 2660);
DISPLAY 0.680851 (1510 2660);
PAINT MONO (1510 2660);
FORCEPROP 0 LASTPIN (1500 3750) $PN 45
J 0
(1510 3760);
DISPLAY 0.680851 (1510 3760);
PAINT MONO (1510 3760);
FORCEPROP 0 LASTPIN (1500 3800) $PN 44
J 0
(1510 3810);
DISPLAY 0.680851 (1510 3810);
PAINT MONO (1510 3810);
FORCEPROP 0 LASTPIN (1500 2700) $PN 138
J 0
(1510 2710);
DISPLAY 0.680851 (1510 2710);
PAINT MONO (1510 2710);
FORCEPROP 0 LASTPIN (1500 2750) $PN 137
J 0
(1510 2760);
DISPLAY 0.680851 (1510 2760);
PAINT MONO (1510 2760);
FORCEPROP 0 LASTPIN (1500 3850) $PN 56
J 0
(1510 3860);
DISPLAY 0.680851 (1510 3860);
PAINT MONO (1510 3860);
FORCEPROP 0 LASTPIN (1500 3900) $PN 55
J 0
(1510 3910);
DISPLAY 0.680851 (1510 3910);
PAINT MONO (1510 3910);
FORCEPROP 0 LASTPIN (1500 2800) $PN 238
J 0
(1510 2810);
DISPLAY 0.680851 (1510 2810);
PAINT MONO (1510 2810);
FORCEPROP 0 LASTPIN (1500 2850) $PN 239
J 0
(1510 2860);
DISPLAY 0.680851 (1510 2860);
PAINT MONO (1510 2860);
FORCEPROP 0 LASTPIN (1500 3950) $PN 156
J 0
(1510 3960);
DISPLAY 0.680851 (1510 3960);
PAINT MONO (1510 3960);
FORCEPROP 0 LASTPIN (1500 4000) $PN 157
J 0
(1510 4010);
DISPLAY 0.680851 (1510 4010);
PAINT MONO (1510 4010);
FORCEPROP 0 LASTPIN (1500 2900) $PN 249
J 0
(1510 2910);
DISPLAY 0.680851 (1510 2910);
PAINT MONO (1510 2910);
FORCEPROP 0 LASTPIN (1500 2950) $PN 250
J 0
(1510 2960);
DISPLAY 0.680851 (1510 2960);
PAINT MONO (1510 2960);
FORCEPROP 0 LASTPIN (1500 4050) $PN 167
J 0
(1510 4060);
DISPLAY 0.680851 (1510 4060);
PAINT MONO (1510 4060);
FORCEPROP 0 LASTPIN (1500 4100) $PN 168
J 0
(1510 4110);
DISPLAY 0.680851 (1510 4110);
PAINT MONO (1510 4110);
FORCEPROP 0 LASTPIN (1500 3000) $PN 260
J 0
(1510 3010);
DISPLAY 0.680851 (1510 3010);
PAINT MONO (1510 3010);
FORCEPROP 0 LASTPIN (1500 3050) $PN 261
J 0
(1510 3060);
DISPLAY 0.680851 (1510 3060);
PAINT MONO (1510 3060);
FORCEPROP 0 LASTPIN (1500 4150) $PN 178
J 0
(1510 4160);
DISPLAY 0.680851 (1510 4160);
PAINT MONO (1510 4160);
FORCEPROP 0 LASTPIN (1500 4200) $PN 179
J 0
(1510 4210);
DISPLAY 0.680851 (1510 4210);
PAINT MONO (1510 4210);
FORCEPROP 0 LASTPIN (1500 3100) $PN 271
J 0
(1510 3110);
DISPLAY 0.680851 (1510 3110);
PAINT MONO (1510 3110);
FORCEPROP 0 LASTPIN (1500 3150) $PN 272
J 0
(1510 3160);
DISPLAY 0.680851 (1510 3160);
PAINT MONO (1510 3160);
FORCEPROP 0 LASTPIN (1500 4250) $PN 189
J 0
(1510 4260);
DISPLAY 0.680851 (1510 4260);
PAINT MONO (1510 4260);
FORCEPROP 0 LASTPIN (1500 4300) $PN 190
J 0
(1510 4310);
DISPLAY 0.680851 (1510 4310);
PAINT MONO (1510 4310);
FORCEPROP 0 LASTPIN (1500 3200) $PN 282
J 0
(1510 3210);
DISPLAY 0.680851 (1510 3210);
PAINT MONO (1510 3210);
FORCEPROP 0 LASTPIN (1500 3250) $PN 283
J 0
(1510 3260);
DISPLAY 0.680851 (1510 3260);
PAINT MONO (1510 3260);
FORCEPROP 0 LASTPIN (1500 4350) $PN 200
J 0
(1510 4360);
DISPLAY 0.680851 (1510 4360);
PAINT MONO (1510 4360);
FORCEPROP 0 LASTPIN (1500 4400) $PN 201
J 0
(1510 4410);
DISPLAY 0.680851 (1510 4410);
PAINT MONO (1510 4410);
FORCEPROP 0 LASTPIN (1500 3300) $PN 94
J 0
(1510 3310);
DISPLAY 0.680851 (1510 3310);
PAINT MONO (1510 3310);
FORCEPROP 0 LASTPIN (1500 3350) $PN 93
J 0
(1510 3360);
DISPLAY 0.680851 (1510 3360);
PAINT MONO (1510 3360);
FORCEPROP 1 LAST CDS_LMAN_SYM_OUTLINE -600,1150,600,-1150
J 0
(750 3400);
DISPLAY 0.468085 (750 3400);
PAINT GREEN (750 3400);
DISPLAY INVISIBLE (750 3400);
FORCEPROP 2 LAST CDS_LIB pure_quanta
J 0
(750 3400);
DISPLAY INVISIBLE (750 3400);
FORCEPROP 1 LAST NEEDS_NO_SIZE TRUE
J 0
(750 3400);
DISPLAY 0.723404 (750 3400);
PAINT GREEN (750 3400);
DISPLAY INVISIBLE (750 3400);
FORCEPROP 0 LAST $SEC 2
J 0
(175 4925);
DISPLAY 0.680851 (175 4925);
PAINT MONO (175 4925);
DISPLAY INVISIBLE (175 4925);
FORCEPROP 0 LAST CDS_SEC 2
J 0
(175 4925);
DISPLAY 1.021277 (175 4925);
DISPLAY INVISIBLE (175 4925);
FORCEPROP 1 LAST PATH I178
J 0
(750 3400);
DISPLAY 0.723404 (750 3400);
PAINT GREEN (750 3400);
DISPLAY INVISIBLE (750 3400);
FORCEADD Q_RES..1
(-3725 1700);
FORCEPROP 1 LAST PART_NUMBER CS04992FB07
J 0
(-3625 1675);
DISPLAY 0.404255 (-3625 1675);
DISPLAY INVISIBLE (-3625 1675);
FORCEPROP 1 LAST MATERIAL CHIP
J 0
(-3950 1675);
DISPLAY 0.404255 (-3950 1675);
FORCEPROP 1 LAST VALUE 49.9
J 2
(-3500 1700);
DISPLAY 0.510638 (-3500 1700);
FORCEPROP 1 LAST $LOCATION R3885
J 0
(-3975 1700);
DISPLAY 0.638298 (-3975 1700);
FORCEPROP 1 LASTPIN (-3825 1700) $PN 1
J 0
(-3813 1712);
DISPLAY 0.787234 (-3813 1712);
PAINT MONO (-3813 1712);
FORCEPROP 1 LASTPIN (-3625 1700) $PN 2
J 0
(-3663 1712);
DISPLAY 0.787234 (-3663 1712);
PAINT MONO (-3663 1712);
FORCEPROP 2 LAST CDS_LIB pure_quanta
J 0
(-3725 1700);
DISPLAY INVISIBLE (-3725 1700);
FORCEPROP 1 LAST PACK_TYPE 0402LF
J 0
(-3425 1700);
DISPLAY 0.510638 (-3425 1700);
DISPLAY INVISIBLE (-3425 1700);
FORCEPROP 1 LAST TOLERANCE 1%
J 0
(-3500 1700);
DISPLAY 0.510638 (-3500 1700);
DISPLAY INVISIBLE (-3500 1700);
FORCEPROP 1 LAST WATTAGE 1/16W
J 2
(-3425 1650);
DISPLAY 0.404255 (-3425 1650);
DISPLAY INVISIBLE (-3425 1650);
FORCEPROP 0 LAST CDS_LOCATION R3885
J 0
(-3875 1750);
DISPLAY 1.021277 (-3875 1750);
DISPLAY INVISIBLE (-3875 1750);
FORCEPROP 0 LAST $SEC 1
J 0
(-3875 1750);
DISPLAY 0.680851 (-3875 1750);
PAINT MONO (-3875 1750);
DISPLAY INVISIBLE (-3875 1750);
FORCEPROP 0 LAST CDS_SEC 1
J 0
(-3875 1750);
DISPLAY 1.021277 (-3875 1750);
DISPLAY INVISIBLE (-3875 1750);
FORCEPROP 1 LAST PATH I179
J 0
(-3775 1850);
DISPLAY 0.978723 (-3775 1850);
PAINT WHITE (-3775 1850);
DISPLAY INVISIBLE (-3775 1850);
FORCEADD OFFPAGE..1
(-3675 3250);
FORCEPROP 2 LAST $XR0 25 
J 0
(-3896 3250);
DISPLAY 0.638298 (-3896 3250);
PAINT MONO (-3896 3250);
FORCEPROP 2 LAST CDS_LIB standard
J 0
(-3675 3250);
PAINT MONO (-3675 3250);
DISPLAY INVISIBLE (-3675 3250);
FORCEPROP 1 LAST OFFPAGE TRUE
J 0
(-3350 3125);
DISPLAY 0.872340 (-3350 3125);
DISPLAY INVISIBLE (-3350 3125);
FORCEPROP 1 LAST COMMENT_BODY TRUE
J 0
(-3550 3150);
DISPLAY 0.872340 (-3550 3150);
PAINT GREEN (-3550 3150);
DISPLAY INVISIBLE (-3550 3150);
FORCEPROP 2 LAST PATH I18
J 0
(-3625 3325);
DISPLAY 1.021277 (-3625 3325);
DISPLAY INVISIBLE (-3625 3325);
FORCEADD OFFPAGE..1
(-2500 1625);
FORCEPROP 2 LAST $XR7 97 
J 0
(-3382 1625);
DISPLAY 0.638298 (-3382 1625);
PAINT MONO (-3382 1625);
FORCEPROP 2 LAST $XR6 96 
J 0
(-3292 1625);
DISPLAY 0.638298 (-3292 1625);
PAINT MONO (-3292 1625);
FORCEPROP 2 LAST $XR5 95 
J 0
(-3202 1625);
DISPLAY 0.638298 (-3202 1625);
PAINT MONO (-3202 1625);
FORCEPROP 2 LAST $XR4 94 
J 0
(-3112 1625);
DISPLAY 0.638298 (-3112 1625);
PAINT MONO (-3112 1625);
FORCEPROP 2 LAST $XR3 93 
J 0
(-3022 1625);
DISPLAY 0.638298 (-3022 1625);
PAINT MONO (-3022 1625);
FORCEPROP 2 LAST $XR2 91 
J 0
(-2932 1625);
DISPLAY 0.638298 (-2932 1625);
PAINT MONO (-2932 1625);
FORCEPROP 2 LAST $XR1 90 
J 0
(-2842 1625);
DISPLAY 0.638298 (-2842 1625);
PAINT MONO (-2842 1625);
FORCEPROP 2 LAST $XR0 229 
J 0
(-2752 1625);
DISPLAY 0.638298 (-2752 1625);
PAINT MONO (-2752 1625);
FORCEPROP 2 LAST CDS_LIB standard
J 2
(-2500 1625);
DISPLAY INVISIBLE (-2500 1625);
FORCEPROP 1 LAST OFFPAGE TRUE
J 0
(-2175 1500);
DISPLAY 0.872340 (-2175 1500);
DISPLAY INVISIBLE (-2175 1500);
FORCEPROP 1 LAST COMMENT_BODY TRUE
J 0
(-2375 1525);
DISPLAY 0.872340 (-2375 1525);
PAINT GREEN (-2375 1525);
DISPLAY INVISIBLE (-2375 1525);
FORCEPROP 2 LAST PATH I180
J 2
(-2675 1700);
DISPLAY 1.021277 (-2675 1700);
DISPLAY INVISIBLE (-2675 1700);
FORCEADD OFFPAGE..1
(-3675 3400);
FORCEPROP 2 LAST $XR0 25 
J 0
(-3896 3400);
DISPLAY 0.638298 (-3896 3400);
PAINT MONO (-3896 3400);
FORCEPROP 2 LAST CDS_LIB standard
J 0
(-3675 3400);
PAINT MONO (-3675 3400);
DISPLAY INVISIBLE (-3675 3400);
FORCEPROP 1 LAST OFFPAGE TRUE
J 0
(-3350 3275);
DISPLAY 0.872340 (-3350 3275);
DISPLAY INVISIBLE (-3350 3275);
FORCEPROP 1 LAST COMMENT_BODY TRUE
J 0
(-3550 3300);
DISPLAY 0.872340 (-3550 3300);
PAINT GREEN (-3550 3300);
DISPLAY INVISIBLE (-3550 3300);
FORCEPROP 2 LAST PATH I19
J 0
(-3625 3475);
DISPLAY 1.021277 (-3625 3475);
DISPLAY INVISIBLE (-3625 3475);
FORCEADD Q_RES..2
(-2525 250);
FORCEPROP 1 LAST PART_NUMBER CS32322FB03
J 0
(-2485 125);
DISPLAY 0.978723 (-2485 125);
DISPLAY INVISIBLE (-2485 125);
FORCEPROP 1 LAST VALUE 23.2K
J 0
(-2480 325);
DISPLAY 0.978723 (-2480 325);
FORCEPROP 1 LAST TOLERANCE 1%
J 0
(-2480 275);
DISPLAY 0.978723 (-2480 275);
FORCEPROP 1 LAST WATTAGE 1/16W
J 0
(-2485 225);
DISPLAY 0.978723 (-2485 225);
FORCEPROP 1 LAST MATERIAL CHIP
J 0
(-2485 175);
DISPLAY 0.978723 (-2485 175);
FORCEPROP 1 LAST PACK_TYPE 0402LF
J 0
(-2485 75);
DISPLAY 0.978723 (-2485 75);
FORCEPROP 1 LAST $LOCATION R36
J 0
(-2480 375);
DISPLAY 0.978723 (-2480 375);
FORCEPROP 1 LASTPIN (-2525 350) $PN 1
J 0
(-2520 312);
DISPLAY 0.787234 (-2520 312);
FORCEPROP 1 LASTPIN (-2525 150) $PN 2
J 0
(-2520 160);
DISPLAY 0.787234 (-2520 160);
FORCEPROP 2 LAST CDS_LIB pure_quanta
J 0
(-2525 250);
PAINT MONO (-2525 250);
DISPLAY INVISIBLE (-2525 250);
FORCEPROP 2 LAST CDS_LOCATION R36
J 0
(-2475 475);
DISPLAY 1.021277 (-2475 475);
DISPLAY INVISIBLE (-2475 475);
FORCEPROP 2 LAST $SEC 1
J 0
(-2475 475);
DISPLAY 0.680851 (-2475 475);
PAINT MONO (-2475 475);
DISPLAY INVISIBLE (-2475 475);
FORCEPROP 2 LAST CDS_SEC 1
J 0
(-2475 475);
DISPLAY 1.021277 (-2475 475);
DISPLAY INVISIBLE (-2475 475);
FORCEPROP 1 LAST PATH I2
J 0
(-2475 425);
DISPLAY 0.978723 (-2475 425);
PAINT WHITE (-2475 425);
DISPLAY INVISIBLE (-2475 425);
FORCEADD OFFPAGE..1
(-3675 3450);
FORCEPROP 2 LAST $XR0 25 
J 0
(-3896 3450);
DISPLAY 0.638298 (-3896 3450);
PAINT MONO (-3896 3450);
FORCEPROP 2 LAST CDS_LIB standard
J 0
(-3675 3450);
PAINT MONO (-3675 3450);
DISPLAY INVISIBLE (-3675 3450);
FORCEPROP 1 LAST OFFPAGE TRUE
J 0
(-3350 3325);
DISPLAY 0.872340 (-3350 3325);
DISPLAY INVISIBLE (-3350 3325);
FORCEPROP 1 LAST COMMENT_BODY TRUE
J 0
(-3550 3350);
DISPLAY 0.872340 (-3550 3350);
PAINT GREEN (-3550 3350);
DISPLAY INVISIBLE (-3550 3350);
FORCEPROP 2 LAST PATH I20
J 0
(-3625 3525);
DISPLAY 1.021277 (-3625 3525);
DISPLAY INVISIBLE (-3625 3525);
FORCEADD OFFPAGE..1
(-3675 3600);
FORCEPROP 2 LAST $XR1 93 
J 0
(-3986 3600);
DISPLAY 0.638298 (-3986 3600);
PAINT MONO (-3986 3600);
FORCEPROP 2 LAST $XR0 25 
J 0
(-3896 3600);
DISPLAY 0.638298 (-3896 3600);
PAINT MONO (-3896 3600);
FORCEPROP 2 LAST CDS_LIB standard
J 0
(-3675 3600);
PAINT MONO (-3675 3600);
DISPLAY INVISIBLE (-3675 3600);
FORCEPROP 1 LAST OFFPAGE TRUE
J 0
(-3350 3475);
DISPLAY 0.872340 (-3350 3475);
DISPLAY INVISIBLE (-3350 3475);
FORCEPROP 1 LAST COMMENT_BODY TRUE
J 0
(-3550 3500);
DISPLAY 0.872340 (-3550 3500);
PAINT GREEN (-3550 3500);
DISPLAY INVISIBLE (-3550 3500);
FORCEPROP 2 LAST PATH I21
J 0
(-3625 3675);
DISPLAY 1.021277 (-3625 3675);
DISPLAY INVISIBLE (-3625 3675);
FORCEADD OFFPAGE..1
(-3675 3550);
FORCEPROP 2 LAST $XR1 93 
J 0
(-3986 3550);
DISPLAY 0.638298 (-3986 3550);
PAINT MONO (-3986 3550);
FORCEPROP 2 LAST $XR0 25 
J 0
(-3896 3550);
DISPLAY 0.638298 (-3896 3550);
PAINT MONO (-3896 3550);
FORCEPROP 2 LAST CDS_LIB standard
J 0
(-3675 3550);
PAINT MONO (-3675 3550);
DISPLAY INVISIBLE (-3675 3550);
FORCEPROP 1 LAST OFFPAGE TRUE
J 0
(-3350 3425);
DISPLAY 0.872340 (-3350 3425);
DISPLAY INVISIBLE (-3350 3425);
FORCEPROP 1 LAST COMMENT_BODY TRUE
J 0
(-3550 3450);
DISPLAY 0.872340 (-3550 3450);
PAINT GREEN (-3550 3450);
DISPLAY INVISIBLE (-3550 3450);
FORCEPROP 2 LAST PATH I22
J 0
(-3625 3625);
DISPLAY 1.021277 (-3625 3625);
DISPLAY INVISIBLE (-3625 3625);
FORCEADD OFFPAGE..1
(-3675 4025);
FORCEPROP 2 LAST $XR1 93 
J 0
(-3986 4025);
DISPLAY 0.638298 (-3986 4025);
PAINT MONO (-3986 4025);
FORCEPROP 2 LAST $XR0 25 
J 0
(-3896 4025);
DISPLAY 0.638298 (-3896 4025);
PAINT MONO (-3896 4025);
FORCEPROP 2 LAST CDS_LIB standard
J 0
(-3675 4025);
PAINT MONO (-3675 4025);
DISPLAY INVISIBLE (-3675 4025);
FORCEPROP 1 LAST OFFPAGE TRUE
J 0
(-3350 3900);
DISPLAY 0.872340 (-3350 3900);
DISPLAY INVISIBLE (-3350 3900);
FORCEPROP 1 LAST COMMENT_BODY TRUE
J 0
(-3550 3925);
DISPLAY 0.872340 (-3550 3925);
PAINT GREEN (-3550 3925);
DISPLAY INVISIBLE (-3550 3925);
FORCEPROP 2 LAST PATH I23
J 0
(-3625 4100);
DISPLAY 1.021277 (-3625 4100);
DISPLAY INVISIBLE (-3625 4100);
FORCEADD OFFPAGE..1
(-3675 4425);
FORCEPROP 2 LAST $XR1 93 
J 0
(-3986 4425);
DISPLAY 0.638298 (-3986 4425);
PAINT MONO (-3986 4425);
FORCEPROP 2 LAST $XR0 25 
J 0
(-3896 4425);
DISPLAY 0.638298 (-3896 4425);
PAINT MONO (-3896 4425);
FORCEPROP 2 LAST CDS_LIB standard
J 0
(-3675 4425);
PAINT MONO (-3675 4425);
DISPLAY INVISIBLE (-3675 4425);
FORCEPROP 1 LAST OFFPAGE TRUE
J 0
(-3350 4300);
DISPLAY 0.872340 (-3350 4300);
DISPLAY INVISIBLE (-3350 4300);
FORCEPROP 1 LAST COMMENT_BODY TRUE
J 0
(-3550 4325);
DISPLAY 0.872340 (-3550 4325);
PAINT GREEN (-3550 4325);
DISPLAY INVISIBLE (-3550 4325);
FORCEPROP 2 LAST PATH I24
J 0
(-3625 4500);
DISPLAY 1.021277 (-3625 4500);
DISPLAY INVISIBLE (-3625 4500);
FORCEADD SCONN288_ADR50017P130CC..1
(-1925 2675);
FORCEPROP 1 LAST PART_NUMBER DFHST8FS461
J 0
(-2370 4697);
DISPLAY 0.723404 (-2370 4697);
PAINT GREEN (-2370 4697);
DISPLAY INVISIBLE (-2370 4697);
FORCEPROP 1 LAST MATERIAL IO
J 0
(-2370 4570);
DISPLAY 0.723404 (-2370 4570);
PAINT GREEN (-2370 4570);
FORCEPROP 2 LAST PART_TYPE SMLF
J 0
(-2375 4850);
DISPLAY 1.021277 (-2375 4850);
FORCEPROP 2 LAST VALUE SCONN288_ADR50017-P130CC
J 0
(-2375 4800);
DISPLAY 1.021277 (-2375 4800);
FORCEPROP 1 LAST $LOCATION J11
J 0
(-2375 4750);
DISPLAY 0.723404 (-2375 4750);
PAINT GREEN (-2375 4750);
FORCEPROP 0 LASTPIN (-2525 2050) $PN 62
J 2
(-2535 2060);
DISPLAY 0.680851 (-2535 2060);
PAINT MONO (-2535 2060);
FORCEPROP 0 LASTPIN (-2525 4100) $PN 66
J 2
(-2535 4110);
DISPLAY 0.680851 (-2535 4110);
PAINT MONO (-2535 4110);
FORCEPROP 0 LASTPIN (-2525 3700) $PN 76
J 2
(-2535 3710);
DISPLAY 0.680851 (-2535 3710);
PAINT MONO (-2535 3710);
FORCEPROP 0 LASTPIN (-2525 4150) $PN 211
J 2
(-2535 4160);
DISPLAY 0.680851 (-2535 4160);
PAINT MONO (-2535 4160);
FORCEPROP 0 LASTPIN (-2525 3750) $PN 221
J 2
(-2535 3760);
DISPLAY 0.680851 (-2535 3760);
PAINT MONO (-2535 3760);
FORCEPROP 0 LASTPIN (-2525 4200) $PN 68
J 2
(-2535 4210);
DISPLAY 0.680851 (-2535 4210);
PAINT MONO (-2535 4210);
FORCEPROP 0 LASTPIN (-2525 3800) $PN 78
J 2
(-2535 3810);
DISPLAY 0.680851 (-2535 3810);
PAINT MONO (-2535 3810);
FORCEPROP 0 LASTPIN (-2525 4250) $PN 213
J 2
(-2535 4260);
DISPLAY 0.680851 (-2535 4260);
PAINT MONO (-2535 4260);
FORCEPROP 0 LASTPIN (-2525 3850) $PN 223
J 2
(-2535 3860);
DISPLAY 0.680851 (-2535 3860);
PAINT MONO (-2535 3860);
FORCEPROP 0 LASTPIN (-2525 4300) $PN 70
J 2
(-2535 4310);
DISPLAY 0.680851 (-2535 4310);
PAINT MONO (-2535 4310);
FORCEPROP 0 LASTPIN (-2525 3900) $PN 80
J 2
(-2535 3910);
DISPLAY 0.680851 (-2535 3910);
PAINT MONO (-2535 3910);
FORCEPROP 0 LASTPIN (-2525 4350) $PN 215
J 2
(-2535 4360);
DISPLAY 0.680851 (-2535 4360);
PAINT MONO (-2535 4360);
FORCEPROP 0 LASTPIN (-2525 3950) $PN 225
J 2
(-2535 3960);
DISPLAY 0.680851 (-2535 3960);
PAINT MONO (-2535 3960);
FORCEPROP 0 LASTPIN (-2525 4400) $PN 72
J 2
(-2535 4410);
DISPLAY 0.680851 (-2535 4410);
PAINT MONO (-2535 4410);
FORCEPROP 0 LASTPIN (-2525 4000) $PN 82
J 2
(-2535 4010);
DISPLAY 0.680851 (-2535 4010);
PAINT MONO (-2535 4010);
FORCEPROP 0 LASTPIN (-2525 2650) $PN 51
J 2
(-2535 2660);
DISPLAY 0.680851 (-2535 2660);
PAINT MONO (-2535 2660);
FORCEPROP 0 LASTPIN (-2525 2200) $PN 96
J 2
(-2535 2210);
DISPLAY 0.680851 (-2535 2210);
PAINT MONO (-2535 2210);
FORCEPROP 0 LASTPIN (-2525 2700) $PN 53
J 2
(-2535 2710);
DISPLAY 0.680851 (-2535 2710);
PAINT MONO (-2535 2710);
FORCEPROP 0 LASTPIN (-2525 2250) $PN 98
J 2
(-2535 2260);
DISPLAY 0.680851 (-2535 2260);
PAINT MONO (-2535 2260);
FORCEPROP 0 LASTPIN (-2525 2750) $PN 196
J 2
(-2535 2760);
DISPLAY 0.680851 (-2535 2760);
PAINT MONO (-2535 2760);
FORCEPROP 0 LASTPIN (-2525 2300) $PN 241
J 2
(-2535 2310);
DISPLAY 0.680851 (-2535 2310);
PAINT MONO (-2535 2310);
FORCEPROP 0 LASTPIN (-2525 2800) $PN 198
J 2
(-2535 2810);
DISPLAY 0.680851 (-2535 2810);
PAINT MONO (-2535 2810);
FORCEPROP 0 LASTPIN (-2525 2350) $PN 243
J 2
(-2535 2360);
DISPLAY 0.680851 (-2535 2360);
PAINT MONO (-2535 2360);
FORCEPROP 0 LASTPIN (-2525 2850) $PN 58
J 2
(-2535 2860);
DISPLAY 0.680851 (-2535 2860);
PAINT MONO (-2535 2860);
FORCEPROP 0 LASTPIN (-2525 2400) $PN 89
J 2
(-2535 2410);
DISPLAY 0.680851 (-2535 2410);
PAINT MONO (-2535 2410);
FORCEPROP 0 LASTPIN (-2525 2900) $PN 60
J 2
(-2535 2910);
DISPLAY 0.680851 (-2535 2910);
PAINT MONO (-2535 2910);
FORCEPROP 0 LASTPIN (-2525 2450) $PN 91
J 2
(-2535 2460);
DISPLAY 0.680851 (-2535 2460);
PAINT MONO (-2535 2460);
FORCEPROP 0 LASTPIN (-2525 2950) $PN 203
J 2
(-2535 2960);
DISPLAY 0.680851 (-2535 2960);
PAINT MONO (-2535 2960);
FORCEPROP 0 LASTPIN (-2525 2500) $PN 234
J 2
(-2535 2510);
DISPLAY 0.680851 (-2535 2510);
PAINT MONO (-2535 2510);
FORCEPROP 0 LASTPIN (-2525 3000) $PN 205
J 2
(-2535 3010);
DISPLAY 0.680851 (-2535 3010);
PAINT MONO (-2535 3010);
FORCEPROP 0 LASTPIN (-2525 2550) $PN 236
J 2
(-2535 2560);
DISPLAY 0.680851 (-2535 2560);
PAINT MONO (-2535 2560);
FORCEPROP 0 LASTPIN (-2525 3100) $PN 218
J 2
(-2535 3110);
DISPLAY 0.680851 (-2535 3110);
PAINT MONO (-2535 3110);
FORCEPROP 0 LASTPIN (-2525 3150) $PN 217
J 2
(-2535 3160);
DISPLAY 0.680851 (-2535 3160);
PAINT MONO (-2535 3160);
FORCEPROP 0 LASTPIN (-2525 3400) $PN 64
J 2
(-2535 3410);
DISPLAY 0.680851 (-2535 3410);
PAINT MONO (-2535 3410);
FORCEPROP 0 LASTPIN (-2525 3250) $PN 84
J 2
(-2535 3260);
DISPLAY 0.680851 (-2535 3260);
PAINT MONO (-2535 3260);
FORCEPROP 0 LASTPIN (-2525 3450) $PN 209
J 2
(-2535 3460);
DISPLAY 0.680851 (-2535 3460);
PAINT MONO (-2535 3460);
FORCEPROP 0 LASTPIN (-2525 3300) $PN 229
J 2
(-2535 3310);
DISPLAY 0.680851 (-2535 3310);
PAINT MONO (-2535 3310);
FORCEPROP 0 LASTPIN (-1325 2850) $PN 7
J 0
(-1315 2860);
DISPLAY 0.680851 (-1315 2860);
PAINT MONO (-1315 2860);
FORCEPROP 0 LASTPIN (-1325 1200) $PN 100
J 0
(-1315 1210);
DISPLAY 0.680851 (-1315 1210);
PAINT MONO (-1315 1210);
FORCEPROP 0 LASTPIN (-1325 2900) $PN 9
J 0
(-1315 2910);
DISPLAY 0.680851 (-1315 2910);
PAINT MONO (-1315 2910);
FORCEPROP 0 LASTPIN (-1325 1250) $PN 102
J 0
(-1315 1260);
DISPLAY 0.680851 (-1315 1260);
PAINT MONO (-1315 1260);
FORCEPROP 0 LASTPIN (-1325 2950) $PN 152
J 0
(-1315 2960);
DISPLAY 0.680851 (-1315 2960);
PAINT MONO (-1315 2960);
FORCEPROP 0 LASTPIN (-1325 1300) $PN 245
J 0
(-1315 1310);
DISPLAY 0.680851 (-1315 1310);
PAINT MONO (-1315 1310);
FORCEPROP 0 LASTPIN (-1325 3000) $PN 154
J 0
(-1315 3010);
DISPLAY 0.680851 (-1315 3010);
PAINT MONO (-1315 3010);
FORCEPROP 0 LASTPIN (-1325 1350) $PN 247
J 0
(-1315 1360);
DISPLAY 0.680851 (-1315 1360);
PAINT MONO (-1315 1360);
FORCEPROP 0 LASTPIN (-1325 3050) $PN 14
J 0
(-1315 3060);
DISPLAY 0.680851 (-1315 3060);
PAINT MONO (-1315 3060);
FORCEPROP 0 LASTPIN (-1325 1400) $PN 107
J 0
(-1315 1410);
DISPLAY 0.680851 (-1315 1410);
PAINT MONO (-1315 1410);
FORCEPROP 0 LASTPIN (-1325 3100) $PN 16
J 0
(-1315 3110);
DISPLAY 0.680851 (-1315 3110);
PAINT MONO (-1315 3110);
FORCEPROP 0 LASTPIN (-1325 1450) $PN 109
J 0
(-1315 1460);
DISPLAY 0.680851 (-1315 1460);
PAINT MONO (-1315 1460);
FORCEPROP 0 LASTPIN (-1325 3150) $PN 159
J 0
(-1315 3160);
DISPLAY 0.680851 (-1315 3160);
PAINT MONO (-1315 3160);
FORCEPROP 0 LASTPIN (-1325 1500) $PN 252
J 0
(-1315 1510);
DISPLAY 0.680851 (-1315 1510);
PAINT MONO (-1315 1510);
FORCEPROP 0 LASTPIN (-1325 3200) $PN 161
J 0
(-1315 3210);
DISPLAY 0.680851 (-1315 3210);
PAINT MONO (-1315 3210);
FORCEPROP 0 LASTPIN (-1325 1550) $PN 254
J 0
(-1315 1560);
DISPLAY 0.680851 (-1315 1560);
PAINT MONO (-1315 1560);
FORCEPROP 0 LASTPIN (-1325 3250) $PN 18
J 0
(-1315 3260);
DISPLAY 0.680851 (-1315 3260);
PAINT MONO (-1315 3260);
FORCEPROP 0 LASTPIN (-1325 1600) $PN 111
J 0
(-1315 1610);
DISPLAY 0.680851 (-1315 1610);
PAINT MONO (-1315 1610);
FORCEPROP 0 LASTPIN (-1325 3300) $PN 20
J 0
(-1315 3310);
DISPLAY 0.680851 (-1315 3310);
PAINT MONO (-1315 3310);
FORCEPROP 0 LASTPIN (-1325 1650) $PN 113
J 0
(-1315 1660);
DISPLAY 0.680851 (-1315 1660);
PAINT MONO (-1315 1660);
FORCEPROP 0 LASTPIN (-1325 3350) $PN 163
J 0
(-1315 3360);
DISPLAY 0.680851 (-1315 3360);
PAINT MONO (-1315 3360);
FORCEPROP 0 LASTPIN (-1325 1700) $PN 256
J 0
(-1315 1710);
DISPLAY 0.680851 (-1315 1710);
PAINT MONO (-1315 1710);
FORCEPROP 0 LASTPIN (-1325 3400) $PN 165
J 0
(-1315 3410);
DISPLAY 0.680851 (-1315 3410);
PAINT MONO (-1315 3410);
FORCEPROP 0 LASTPIN (-1325 1750) $PN 258
J 0
(-1315 1760);
DISPLAY 0.680851 (-1315 1760);
PAINT MONO (-1315 1760);
FORCEPROP 0 LASTPIN (-1325 3450) $PN 25
J 0
(-1315 3460);
DISPLAY 0.680851 (-1315 3460);
PAINT MONO (-1315 3460);
FORCEPROP 0 LASTPIN (-1325 1800) $PN 118
J 0
(-1315 1810);
DISPLAY 0.680851 (-1315 1810);
PAINT MONO (-1315 1810);
FORCEPROP 0 LASTPIN (-1325 3500) $PN 27
J 0
(-1315 3510);
DISPLAY 0.680851 (-1315 3510);
PAINT MONO (-1315 3510);
FORCEPROP 0 LASTPIN (-1325 1850) $PN 120
J 0
(-1315 1860);
DISPLAY 0.680851 (-1315 1860);
PAINT MONO (-1315 1860);
FORCEPROP 0 LASTPIN (-1325 3550) $PN 170
J 0
(-1315 3560);
DISPLAY 0.680851 (-1315 3560);
PAINT MONO (-1315 3560);
FORCEPROP 0 LASTPIN (-1325 1900) $PN 263
J 0
(-1315 1910);
DISPLAY 0.680851 (-1315 1910);
PAINT MONO (-1315 1910);
FORCEPROP 0 LASTPIN (-1325 3600) $PN 172
J 0
(-1315 3610);
DISPLAY 0.680851 (-1315 3610);
PAINT MONO (-1315 3610);
FORCEPROP 0 LASTPIN (-1325 1950) $PN 265
J 0
(-1315 1960);
DISPLAY 0.680851 (-1315 1960);
PAINT MONO (-1315 1960);
FORCEPROP 0 LASTPIN (-1325 3650) $PN 29
J 0
(-1315 3660);
DISPLAY 0.680851 (-1315 3660);
PAINT MONO (-1315 3660);
FORCEPROP 0 LASTPIN (-1325 2000) $PN 122
J 0
(-1315 2010);
DISPLAY 0.680851 (-1315 2010);
PAINT MONO (-1315 2010);
FORCEPROP 0 LASTPIN (-1325 3700) $PN 31
J 0
(-1315 3710);
DISPLAY 0.680851 (-1315 3710);
PAINT MONO (-1315 3710);
FORCEPROP 0 LASTPIN (-1325 2050) $PN 124
J 0
(-1315 2060);
DISPLAY 0.680851 (-1315 2060);
PAINT MONO (-1315 2060);
FORCEPROP 0 LASTPIN (-1325 3750) $PN 174
J 0
(-1315 3760);
DISPLAY 0.680851 (-1315 3760);
PAINT MONO (-1315 3760);
FORCEPROP 0 LASTPIN (-1325 2100) $PN 267
J 0
(-1315 2110);
DISPLAY 0.680851 (-1315 2110);
PAINT MONO (-1315 2110);
FORCEPROP 0 LASTPIN (-1325 3800) $PN 176
J 0
(-1315 3810);
DISPLAY 0.680851 (-1315 3810);
PAINT MONO (-1315 3810);
FORCEPROP 0 LASTPIN (-1325 2150) $PN 269
J 0
(-1315 2160);
DISPLAY 0.680851 (-1315 2160);
PAINT MONO (-1315 2160);
FORCEPROP 0 LASTPIN (-1325 3850) $PN 36
J 0
(-1315 3860);
DISPLAY 0.680851 (-1315 3860);
PAINT MONO (-1315 3860);
FORCEPROP 0 LASTPIN (-1325 2200) $PN 129
J 0
(-1315 2210);
DISPLAY 0.680851 (-1315 2210);
PAINT MONO (-1315 2210);
FORCEPROP 0 LASTPIN (-1325 3900) $PN 38
J 0
(-1315 3910);
DISPLAY 0.680851 (-1315 3910);
PAINT MONO (-1315 3910);
FORCEPROP 0 LASTPIN (-1325 2250) $PN 131
J 0
(-1315 2260);
DISPLAY 0.680851 (-1315 2260);
PAINT MONO (-1315 2260);
FORCEPROP 0 LASTPIN (-1325 3950) $PN 181
J 0
(-1315 3960);
DISPLAY 0.680851 (-1315 3960);
PAINT MONO (-1315 3960);
FORCEPROP 0 LASTPIN (-1325 2300) $PN 274
J 0
(-1315 2310);
DISPLAY 0.680851 (-1315 2310);
PAINT MONO (-1315 2310);
FORCEPROP 0 LASTPIN (-1325 4000) $PN 183
J 0
(-1315 4010);
DISPLAY 0.680851 (-1315 4010);
PAINT MONO (-1315 4010);
FORCEPROP 0 LASTPIN (-1325 2350) $PN 276
J 0
(-1315 2360);
DISPLAY 0.680851 (-1315 2360);
PAINT MONO (-1315 2360);
FORCEPROP 0 LASTPIN (-1325 4050) $PN 40
J 0
(-1315 4060);
DISPLAY 0.680851 (-1315 4060);
PAINT MONO (-1315 4060);
FORCEPROP 0 LASTPIN (-1325 2400) $PN 133
J 0
(-1315 2410);
DISPLAY 0.680851 (-1315 2410);
PAINT MONO (-1315 2410);
FORCEPROP 0 LASTPIN (-1325 4100) $PN 42
J 0
(-1315 4110);
DISPLAY 0.680851 (-1315 4110);
PAINT MONO (-1315 4110);
FORCEPROP 0 LASTPIN (-1325 2450) $PN 135
J 0
(-1315 2460);
DISPLAY 0.680851 (-1315 2460);
PAINT MONO (-1315 2460);
FORCEPROP 0 LASTPIN (-1325 4150) $PN 185
J 0
(-1315 4160);
DISPLAY 0.680851 (-1315 4160);
PAINT MONO (-1315 4160);
FORCEPROP 0 LASTPIN (-1325 2500) $PN 278
J 0
(-1315 2510);
DISPLAY 0.680851 (-1315 2510);
PAINT MONO (-1315 2510);
FORCEPROP 0 LASTPIN (-1325 4200) $PN 187
J 0
(-1315 4210);
DISPLAY 0.680851 (-1315 4210);
PAINT MONO (-1315 4210);
FORCEPROP 0 LASTPIN (-1325 2550) $PN 280
J 0
(-1315 2560);
DISPLAY 0.680851 (-1315 2560);
PAINT MONO (-1315 2560);
FORCEPROP 0 LASTPIN (-1325 4250) $PN 47
J 0
(-1315 4260);
DISPLAY 0.680851 (-1315 4260);
PAINT MONO (-1315 4260);
FORCEPROP 0 LASTPIN (-1325 2600) $PN 140
J 0
(-1315 2610);
DISPLAY 0.680851 (-1315 2610);
PAINT MONO (-1315 2610);
FORCEPROP 0 LASTPIN (-1325 4300) $PN 49
J 0
(-1315 4310);
DISPLAY 0.680851 (-1315 4310);
PAINT MONO (-1315 4310);
FORCEPROP 0 LASTPIN (-1325 2650) $PN 142
J 0
(-1315 2660);
DISPLAY 0.680851 (-1315 2660);
PAINT MONO (-1315 2660);
FORCEPROP 0 LASTPIN (-1325 4350) $PN 192
J 0
(-1315 4360);
DISPLAY 0.680851 (-1315 4360);
PAINT MONO (-1315 4360);
FORCEPROP 0 LASTPIN (-1325 2700) $PN 285
J 0
(-1315 2710);
DISPLAY 0.680851 (-1315 2710);
PAINT MONO (-1315 2710);
FORCEPROP 0 LASTPIN (-1325 4400) $PN 194
J 0
(-1315 4410);
DISPLAY 0.680851 (-1315 4410);
PAINT MONO (-1315 4410);
FORCEPROP 0 LASTPIN (-1325 2750) $PN 287
J 0
(-1315 2760);
DISPLAY 0.680851 (-1315 2760);
PAINT MONO (-1315 2760);
FORCEPROP 0 LASTPIN (-2525 1900) $PN 148
J 2
(-2535 1910);
DISPLAY 0.680851 (-2535 1910);
PAINT MONO (-2535 1910);
FORCEPROP 0 LASTPIN (-2525 1800) $PN 4
J 2
(-2535 1810);
DISPLAY 0.680851 (-2535 1810);
PAINT MONO (-2535 1810);
FORCEPROP 0 LASTPIN (-2525 1850) $PN 5
J 2
(-2535 1860);
DISPLAY 0.680851 (-2535 1860);
PAINT MONO (-2535 1860);
FORCEPROP 0 LASTPIN (-2525 1000) $PN 86
J 2
(-2535 1010);
DISPLAY 0.680851 (-2535 1010);
PAINT MONO (-2535 1010);
FORCEPROP 0 LASTPIN (-2525 950) $PN 87
J 2
(-2535 960);
DISPLAY 0.680851 (-2535 960);
PAINT MONO (-2535 960);
FORCEPROP 0 LASTPIN (-2525 3600) $PN 74
J 2
(-2535 3610);
DISPLAY 0.680851 (-2535 3610);
PAINT MONO (-2535 3610);
FORCEPROP 0 LASTPIN (-2525 3550) $PN 227
J 2
(-2535 3560);
DISPLAY 0.680851 (-2535 3560);
PAINT MONO (-2535 3560);
FORCEPROP 0 LASTPIN (-2525 1550) $PN 147
J 2
(-2535 1560);
DISPLAY 0.680851 (-2535 1560);
PAINT MONO (-2535 1560);
FORCEPROP 0 LASTPIN (-2525 2100) $PN 207
J 2
(-2535 2110);
DISPLAY 0.680851 (-2535 2110);
PAINT MONO (-2535 2110);
FORCEPROP 0 LASTPIN (-2525 1150) $PN 2
J 2
(-2535 1160);
DISPLAY 0.680851 (-2535 1160);
PAINT MONO (-2535 1160);
FORCEPROP 0 LASTPIN (-2525 1200) $PN 144
J 2
(-2535 1210);
DISPLAY 0.680851 (-2535 1210);
PAINT MONO (-2535 1210);
FORCEPROP 0 LASTPIN (-2525 1250) $PN 149
J 2
(-2535 1260);
DISPLAY 0.680851 (-2535 1260);
PAINT MONO (-2535 1260);
FORCEPROP 0 LASTPIN (-2525 1300) $PN 150
J 2
(-2535 1310);
DISPLAY 0.680851 (-2535 1310);
PAINT MONO (-2535 1310);
FORCEPROP 0 LASTPIN (-2525 1350) $PN 220
J 2
(-2535 1360);
DISPLAY 0.680851 (-2535 1360);
PAINT MONO (-2535 1360);
FORCEPROP 0 LASTPIN (-2525 1400) $PN 231
J 2
(-2535 1410);
DISPLAY 0.680851 (-2535 1410);
PAINT MONO (-2535 1410);
FORCEPROP 0 LASTPIN (-2525 1450) $PN 232
J 2
(-2535 1460);
DISPLAY 0.680851 (-2535 1460);
PAINT MONO (-2535 1460);
FORCEPROP 0 LASTPIN (-2525 1950) $PN 3
J 2
(-2535 1960);
DISPLAY 0.680851 (-2535 1960);
PAINT MONO (-2535 1960);
FORCEPROP 1 LAST NEEDS_NO_SIZE TRUE
J 0
(-1925 2675);
DISPLAY 0.723404 (-1925 2675);
PAINT GREEN (-1925 2675);
DISPLAY INVISIBLE (-1925 2675);
FORCEPROP 1 LAST CDS_LMAN_SYM_OUTLINE -450,1875,450,-1875
J 0
(-1925 2675);
DISPLAY 0.468085 (-1925 2675);
PAINT GREEN (-1925 2675);
DISPLAY INVISIBLE (-1925 2675);
FORCEPROP 2 LAST CDS_LIB pure_quanta
J 0
(-1925 2675);
DISPLAY INVISIBLE (-1925 2675);
FORCEPROP 2 LAST CDS_LOCATION J11
J 0
(-2375 4900);
DISPLAY 1.021277 (-2375 4900);
DISPLAY INVISIBLE (-2375 4900);
FORCEPROP 0 LAST $SEC 1
J 0
(-2375 4900);
DISPLAY 0.680851 (-2375 4900);
PAINT MONO (-2375 4900);
DISPLAY INVISIBLE (-2375 4900);
FORCEPROP 2 LAST CDS_SEC 1
J 0
(-2375 4900);
DISPLAY 1.021277 (-2375 4900);
DISPLAY INVISIBLE (-2375 4900);
FORCEPROP 1 LAST PATH I25
J 0
(-1925 2675);
DISPLAY 0.723404 (-1925 2675);
PAINT GREEN (-1925 2675);
DISPLAY INVISIBLE (-1925 2675);
FORCEADD TAP..1
R 2
(-2750 2350);
FORCEPROP 3 LASTPIN (-2700 2350) SIG_NAME M_F_CPU0_SB_CB<3>
J 0
(-2690 2360);
DISPLAY 0.659574 (-2690 2360);
PAINT MONO (-2690 2360);
DISPLAY INVISIBLE (-2690 2360);
FORCEPROP 1 LASTPIN (-2700 2350) BN 3
J 2
(-2688 2358);
DISPLAY 0.680851 (-2688 2358);
PAINT GREEN (-2688 2358);
FORCEPROP 2 LAST CDS_LIB standard
J 0
(-2750 2350);
DISPLAY INVISIBLE (-2750 2350);
FORCEPROP 1 LAST BODY_TYPE PLUMBING
J 2
(-2750 2400);
DISPLAY 0.872340 (-2750 2400);
PAINT GREEN (-2750 2400);
DISPLAY INVISIBLE (-2750 2400);
FORCEPROP 1 LAST HDL_TAP TRUE
J 2
(-3075 2225);
DISPLAY 0.872340 (-3075 2225);
DISPLAY INVISIBLE (-3075 2225);
FORCEPROP 1 LAST PATH I26
J 2
(-2748 2350);
DISPLAY 0.872340 (-2748 2350);
PAINT GREEN (-2748 2350);
DISPLAY INVISIBLE (-2748 2350);
FORCEADD TAP..1
R 2
(-2750 2300);
FORCEPROP 3 LASTPIN (-2700 2300) SIG_NAME M_F_CPU0_SB_CB<2>
J 0
(-2690 2310);
DISPLAY 0.659574 (-2690 2310);
PAINT MONO (-2690 2310);
DISPLAY INVISIBLE (-2690 2310);
FORCEPROP 1 LASTPIN (-2700 2300) BN 2
J 2
(-2688 2308);
DISPLAY 0.680851 (-2688 2308);
PAINT GREEN (-2688 2308);
FORCEPROP 2 LAST CDS_LIB standard
J 0
(-2750 2300);
DISPLAY INVISIBLE (-2750 2300);
FORCEPROP 1 LAST BODY_TYPE PLUMBING
J 2
(-2750 2350);
DISPLAY 0.872340 (-2750 2350);
PAINT GREEN (-2750 2350);
DISPLAY INVISIBLE (-2750 2350);
FORCEPROP 1 LAST HDL_TAP TRUE
J 2
(-3075 2175);
DISPLAY 0.872340 (-3075 2175);
DISPLAY INVISIBLE (-3075 2175);
FORCEPROP 1 LAST PATH I27
J 2
(-2748 2300);
DISPLAY 0.872340 (-2748 2300);
PAINT GREEN (-2748 2300);
DISPLAY INVISIBLE (-2748 2300);
FORCEADD TAP..1
R 2
(-2750 2200);
FORCEPROP 3 LASTPIN (-2700 2200) SIG_NAME M_F_CPU0_SB_CB<0>
J 0
(-2690 2210);
DISPLAY 0.659574 (-2690 2210);
PAINT MONO (-2690 2210);
DISPLAY INVISIBLE (-2690 2210);
FORCEPROP 1 LASTPIN (-2700 2200) BN 0
J 2
(-2688 2208);
DISPLAY 0.680851 (-2688 2208);
PAINT GREEN (-2688 2208);
FORCEPROP 2 LAST CDS_LIB standard
J 0
(-2750 2200);
PAINT MONO (-2750 2200);
DISPLAY INVISIBLE (-2750 2200);
FORCEPROP 1 LAST BODY_TYPE PLUMBING
J 2
(-2750 2250);
DISPLAY 0.872340 (-2750 2250);
PAINT GREEN (-2750 2250);
DISPLAY INVISIBLE (-2750 2250);
FORCEPROP 1 LAST HDL_TAP TRUE
J 2
(-3075 2075);
DISPLAY 0.872340 (-3075 2075);
DISPLAY INVISIBLE (-3075 2075);
FORCEPROP 1 LAST PATH I28
J 2
(-2748 2200);
DISPLAY 0.872340 (-2748 2200);
PAINT GREEN (-2748 2200);
DISPLAY INVISIBLE (-2748 2200);
FORCEADD TAP..1
R 2
(-2750 2250);
FORCEPROP 3 LASTPIN (-2700 2250) SIG_NAME M_F_CPU0_SB_CB<1>
J 0
(-2690 2260);
DISPLAY 0.659574 (-2690 2260);
PAINT MONO (-2690 2260);
DISPLAY INVISIBLE (-2690 2260);
FORCEPROP 1 LASTPIN (-2700 2250) BN 1
J 2
(-2688 2258);
DISPLAY 0.680851 (-2688 2258);
PAINT GREEN (-2688 2258);
FORCEPROP 2 LAST CDS_LIB standard
J 0
(-2750 2250);
DISPLAY INVISIBLE (-2750 2250);
FORCEPROP 1 LAST BODY_TYPE PLUMBING
J 2
(-2750 2300);
DISPLAY 0.872340 (-2750 2300);
PAINT GREEN (-2750 2300);
DISPLAY INVISIBLE (-2750 2300);
FORCEPROP 1 LAST HDL_TAP TRUE
J 2
(-3075 2125);
DISPLAY 0.872340 (-3075 2125);
DISPLAY INVISIBLE (-3075 2125);
FORCEPROP 1 LAST PATH I29
J 2
(-2748 2250);
DISPLAY 0.872340 (-2748 2250);
PAINT GREEN (-2748 2250);
DISPLAY INVISIBLE (-2748 2250);
FORCEADD OFFPAGE..2
R 2
(-3675 450);
FORCEPROP 2 LAST $XR0 92 
J 0
(-3899 450);
DISPLAY 0.638298 (-3899 450);
PAINT MONO (-3899 450);
FORCEPROP 2 LAST CDS_LIB standard
J 0
(-3675 450);
PAINT MONO (-3675 450);
DISPLAY INVISIBLE (-3675 450);
FORCEPROP 1 LAST OFFPAGE TRUE
J 2
(-4000 325);
DISPLAY 0.872340 (-4000 325);
DISPLAY INVISIBLE (-4000 325);
FORCEPROP 1 LAST COMMENT_BODY TRUE
J 2
(-3630 355);
DISPLAY 0.872340 (-3630 355);
PAINT GREEN (-3630 355);
DISPLAY INVISIBLE (-3630 355);
FORCEPROP 2 LAST PATH I3
J 0
(-3625 525);
DISPLAY 1.021277 (-3625 525);
DISPLAY INVISIBLE (-3625 525);
FORCEADD TAP..1
R 2
(-2750 2400);
FORCEPROP 3 LASTPIN (-2700 2400) SIG_NAME M_F_CPU0_SB_CB<4>
J 0
(-2690 2410);
DISPLAY 0.659574 (-2690 2410);
PAINT MONO (-2690 2410);
DISPLAY INVISIBLE (-2690 2410);
FORCEPROP 1 LASTPIN (-2700 2400) BN 4
J 2
(-2688 2408);
DISPLAY 0.680851 (-2688 2408);
PAINT GREEN (-2688 2408);
FORCEPROP 2 LAST CDS_LIB standard
J 0
(-2750 2400);
DISPLAY INVISIBLE (-2750 2400);
FORCEPROP 1 LAST BODY_TYPE PLUMBING
J 2
(-2750 2450);
DISPLAY 0.872340 (-2750 2450);
PAINT GREEN (-2750 2450);
DISPLAY INVISIBLE (-2750 2450);
FORCEPROP 1 LAST HDL_TAP TRUE
J 2
(-3075 2275);
DISPLAY 0.872340 (-3075 2275);
DISPLAY INVISIBLE (-3075 2275);
FORCEPROP 1 LAST PATH I30
J 2
(-2748 2400);
DISPLAY 0.872340 (-2748 2400);
PAINT GREEN (-2748 2400);
DISPLAY INVISIBLE (-2748 2400);
FORCEADD TAP..1
(-1100 1250);
FORCEPROP 3 LASTPIN (-1150 1250) SIG_NAME M_F_CPU0_SB_DQ<1>
J 0
(-1140 1260);
DISPLAY 0.659574 (-1140 1260);
PAINT MONO (-1140 1260);
DISPLAY INVISIBLE (-1140 1260);
FORCEPROP 1 LASTPIN (-1150 1250) BN 1
J 0
(-1162 1258);
DISPLAY 0.680851 (-1162 1258);
PAINT GREEN (-1162 1258);
FORCEPROP 2 LAST CDS_LIB standard
J 0
(-1100 1250);
PAINT MONO (-1100 1250);
DISPLAY INVISIBLE (-1100 1250);
FORCEPROP 1 LAST BODY_TYPE PLUMBING
J 0
(-1100 1300);
DISPLAY 0.872340 (-1100 1300);
PAINT GREEN (-1100 1300);
DISPLAY INVISIBLE (-1100 1300);
FORCEPROP 1 LAST HDL_TAP TRUE
J 0
(-775 1125);
DISPLAY 0.872340 (-775 1125);
DISPLAY INVISIBLE (-775 1125);
FORCEPROP 1 LAST PATH I31
J 0
(-1102 1250);
DISPLAY 0.872340 (-1102 1250);
PAINT GREEN (-1102 1250);
DISPLAY INVISIBLE (-1102 1250);
FORCEADD TAP..1
(-1100 1200);
FORCEPROP 3 LASTPIN (-1150 1200) SIG_NAME M_F_CPU0_SB_DQ<0>
J 0
(-1140 1210);
DISPLAY 0.659574 (-1140 1210);
PAINT MONO (-1140 1210);
DISPLAY INVISIBLE (-1140 1210);
FORCEPROP 1 LASTPIN (-1150 1200) BN 0
J 0
(-1162 1208);
DISPLAY 0.680851 (-1162 1208);
PAINT GREEN (-1162 1208);
FORCEPROP 2 LAST CDS_LIB standard
J 0
(-1100 1200);
PAINT MONO (-1100 1200);
DISPLAY INVISIBLE (-1100 1200);
FORCEPROP 1 LAST BODY_TYPE PLUMBING
J 0
(-1100 1250);
DISPLAY 0.872340 (-1100 1250);
PAINT GREEN (-1100 1250);
DISPLAY INVISIBLE (-1100 1250);
FORCEPROP 1 LAST HDL_TAP TRUE
J 0
(-775 1075);
DISPLAY 0.872340 (-775 1075);
DISPLAY INVISIBLE (-775 1075);
FORCEPROP 1 LAST PATH I32
J 0
(-1102 1200);
DISPLAY 0.872340 (-1102 1200);
PAINT GREEN (-1102 1200);
DISPLAY INVISIBLE (-1102 1200);
FORCEADD TAP..1
(-1100 1300);
FORCEPROP 3 LASTPIN (-1150 1300) SIG_NAME M_F_CPU0_SB_DQ<2>
J 0
(-1140 1310);
DISPLAY 0.659574 (-1140 1310);
PAINT MONO (-1140 1310);
DISPLAY INVISIBLE (-1140 1310);
FORCEPROP 1 LASTPIN (-1150 1300) BN 2
J 0
(-1162 1308);
DISPLAY 0.680851 (-1162 1308);
PAINT GREEN (-1162 1308);
FORCEPROP 2 LAST CDS_LIB standard
J 0
(-1100 1300);
PAINT MONO (-1100 1300);
DISPLAY INVISIBLE (-1100 1300);
FORCEPROP 1 LAST BODY_TYPE PLUMBING
J 0
(-1100 1350);
DISPLAY 0.872340 (-1100 1350);
PAINT GREEN (-1100 1350);
DISPLAY INVISIBLE (-1100 1350);
FORCEPROP 1 LAST HDL_TAP TRUE
J 0
(-775 1175);
DISPLAY 0.872340 (-775 1175);
DISPLAY INVISIBLE (-775 1175);
FORCEPROP 1 LAST PATH I33
J 0
(-1102 1300);
DISPLAY 0.872340 (-1102 1300);
PAINT GREEN (-1102 1300);
DISPLAY INVISIBLE (-1102 1300);
FORCEADD TAP..1
(-1100 1350);
FORCEPROP 3 LASTPIN (-1150 1350) SIG_NAME M_F_CPU0_SB_DQ<3>
J 0
(-1140 1360);
DISPLAY 0.659574 (-1140 1360);
PAINT MONO (-1140 1360);
DISPLAY INVISIBLE (-1140 1360);
FORCEPROP 1 LASTPIN (-1150 1350) BN 3
J 0
(-1162 1358);
DISPLAY 0.680851 (-1162 1358);
PAINT GREEN (-1162 1358);
FORCEPROP 2 LAST CDS_LIB standard
J 0
(-1100 1350);
PAINT MONO (-1100 1350);
DISPLAY INVISIBLE (-1100 1350);
FORCEPROP 1 LAST BODY_TYPE PLUMBING
J 0
(-1100 1400);
DISPLAY 0.872340 (-1100 1400);
PAINT GREEN (-1100 1400);
DISPLAY INVISIBLE (-1100 1400);
FORCEPROP 1 LAST HDL_TAP TRUE
J 0
(-775 1225);
DISPLAY 0.872340 (-775 1225);
DISPLAY INVISIBLE (-775 1225);
FORCEPROP 1 LAST PATH I34
J 0
(-1102 1350);
DISPLAY 0.872340 (-1102 1350);
PAINT GREEN (-1102 1350);
DISPLAY INVISIBLE (-1102 1350);
FORCEADD TAP..1
(-1100 1400);
FORCEPROP 3 LASTPIN (-1150 1400) SIG_NAME M_F_CPU0_SB_DQ<4>
J 0
(-1140 1410);
DISPLAY 0.659574 (-1140 1410);
PAINT MONO (-1140 1410);
DISPLAY INVISIBLE (-1140 1410);
FORCEPROP 1 LASTPIN (-1150 1400) BN 4
J 0
(-1162 1408);
DISPLAY 0.680851 (-1162 1408);
PAINT GREEN (-1162 1408);
FORCEPROP 2 LAST CDS_LIB standard
J 0
(-1100 1400);
PAINT MONO (-1100 1400);
DISPLAY INVISIBLE (-1100 1400);
FORCEPROP 1 LAST BODY_TYPE PLUMBING
J 0
(-1100 1450);
DISPLAY 0.872340 (-1100 1450);
PAINT GREEN (-1100 1450);
DISPLAY INVISIBLE (-1100 1450);
FORCEPROP 1 LAST HDL_TAP TRUE
J 0
(-775 1275);
DISPLAY 0.872340 (-775 1275);
DISPLAY INVISIBLE (-775 1275);
FORCEPROP 1 LAST PATH I35
J 0
(-1102 1400);
DISPLAY 0.872340 (-1102 1400);
PAINT GREEN (-1102 1400);
DISPLAY INVISIBLE (-1102 1400);
FORCEADD TAP..1
(-1100 1450);
FORCEPROP 3 LASTPIN (-1150 1450) SIG_NAME M_F_CPU0_SB_DQ<5>
J 0
(-1140 1460);
DISPLAY 0.659574 (-1140 1460);
PAINT MONO (-1140 1460);
DISPLAY INVISIBLE (-1140 1460);
FORCEPROP 1 LASTPIN (-1150 1450) BN 5
J 0
(-1162 1458);
DISPLAY 0.680851 (-1162 1458);
PAINT GREEN (-1162 1458);
FORCEPROP 2 LAST CDS_LIB standard
J 0
(-1100 1450);
PAINT MONO (-1100 1450);
DISPLAY INVISIBLE (-1100 1450);
FORCEPROP 1 LAST BODY_TYPE PLUMBING
J 0
(-1100 1500);
DISPLAY 0.872340 (-1100 1500);
PAINT GREEN (-1100 1500);
DISPLAY INVISIBLE (-1100 1500);
FORCEPROP 1 LAST HDL_TAP TRUE
J 0
(-775 1325);
DISPLAY 0.872340 (-775 1325);
DISPLAY INVISIBLE (-775 1325);
FORCEPROP 1 LAST PATH I36
J 0
(-1102 1450);
DISPLAY 0.872340 (-1102 1450);
PAINT GREEN (-1102 1450);
DISPLAY INVISIBLE (-1102 1450);
FORCEADD TAP..1
(-1100 1500);
FORCEPROP 3 LASTPIN (-1150 1500) SIG_NAME M_F_CPU0_SB_DQ<6>
J 0
(-1140 1510);
DISPLAY 0.659574 (-1140 1510);
PAINT MONO (-1140 1510);
DISPLAY INVISIBLE (-1140 1510);
FORCEPROP 1 LASTPIN (-1150 1500) BN 6
J 0
(-1162 1508);
DISPLAY 0.680851 (-1162 1508);
PAINT GREEN (-1162 1508);
FORCEPROP 2 LAST CDS_LIB standard
J 0
(-1100 1500);
PAINT MONO (-1100 1500);
DISPLAY INVISIBLE (-1100 1500);
FORCEPROP 1 LAST BODY_TYPE PLUMBING
J 0
(-1100 1550);
DISPLAY 0.872340 (-1100 1550);
PAINT GREEN (-1100 1550);
DISPLAY INVISIBLE (-1100 1550);
FORCEPROP 1 LAST HDL_TAP TRUE
J 0
(-775 1375);
DISPLAY 0.872340 (-775 1375);
DISPLAY INVISIBLE (-775 1375);
FORCEPROP 1 LAST PATH I37
J 0
(-1102 1500);
DISPLAY 0.872340 (-1102 1500);
PAINT GREEN (-1102 1500);
DISPLAY INVISIBLE (-1102 1500);
FORCEADD TAP..1
(-1100 1650);
FORCEPROP 3 LASTPIN (-1150 1650) SIG_NAME M_F_CPU0_SB_DQ<9>
J 0
(-1140 1660);
DISPLAY 0.659574 (-1140 1660);
PAINT MONO (-1140 1660);
DISPLAY INVISIBLE (-1140 1660);
FORCEPROP 1 LASTPIN (-1150 1650) BN 9
J 0
(-1162 1658);
DISPLAY 0.680851 (-1162 1658);
PAINT GREEN (-1162 1658);
FORCEPROP 2 LAST CDS_LIB standard
J 0
(-1100 1650);
PAINT MONO (-1100 1650);
DISPLAY INVISIBLE (-1100 1650);
FORCEPROP 1 LAST BODY_TYPE PLUMBING
J 0
(-1100 1700);
DISPLAY 0.872340 (-1100 1700);
PAINT GREEN (-1100 1700);
DISPLAY INVISIBLE (-1100 1700);
FORCEPROP 1 LAST HDL_TAP TRUE
J 0
(-775 1525);
DISPLAY 0.872340 (-775 1525);
DISPLAY INVISIBLE (-775 1525);
FORCEPROP 1 LAST PATH I38
J 0
(-1102 1650);
DISPLAY 0.872340 (-1102 1650);
PAINT GREEN (-1102 1650);
DISPLAY INVISIBLE (-1102 1650);
FORCEADD TAP..1
(-1100 1600);
FORCEPROP 3 LASTPIN (-1150 1600) SIG_NAME M_F_CPU0_SB_DQ<8>
J 0
(-1140 1610);
DISPLAY 0.659574 (-1140 1610);
PAINT MONO (-1140 1610);
DISPLAY INVISIBLE (-1140 1610);
FORCEPROP 1 LASTPIN (-1150 1600) BN 8
J 0
(-1162 1608);
DISPLAY 0.680851 (-1162 1608);
PAINT GREEN (-1162 1608);
FORCEPROP 2 LAST CDS_LIB standard
J 0
(-1100 1600);
PAINT MONO (-1100 1600);
DISPLAY INVISIBLE (-1100 1600);
FORCEPROP 1 LAST BODY_TYPE PLUMBING
J 0
(-1100 1650);
DISPLAY 0.872340 (-1100 1650);
PAINT GREEN (-1100 1650);
DISPLAY INVISIBLE (-1100 1650);
FORCEPROP 1 LAST HDL_TAP TRUE
J 0
(-775 1475);
DISPLAY 0.872340 (-775 1475);
DISPLAY INVISIBLE (-775 1475);
FORCEPROP 1 LAST PATH I39
J 0
(-1102 1600);
DISPLAY 0.872340 (-1102 1600);
PAINT GREEN (-1102 1600);
DISPLAY INVISIBLE (-1102 1600);
FORCEADD OFFPAGE..2
R 2
(-3675 1000);
FORCEPROP 2 LAST $XR0 25 
J 0
(-3899 1000);
DISPLAY 0.638298 (-3899 1000);
PAINT MONO (-3899 1000);
FORCEPROP 2 LAST CDS_LIB standard
J 0
(-3675 1000);
PAINT MONO (-3675 1000);
DISPLAY INVISIBLE (-3675 1000);
FORCEPROP 1 LAST OFFPAGE TRUE
J 2
(-4000 875);
DISPLAY 0.872340 (-4000 875);
DISPLAY INVISIBLE (-4000 875);
FORCEPROP 1 LAST COMMENT_BODY TRUE
J 2
(-3630 905);
DISPLAY 0.872340 (-3630 905);
PAINT GREEN (-3630 905);
DISPLAY INVISIBLE (-3630 905);
FORCEPROP 2 LAST PATH I4
J 0
(-3625 1075);
DISPLAY 1.021277 (-3625 1075);
DISPLAY INVISIBLE (-3625 1075);
FORCEADD TAP..1
(-1100 1550);
FORCEPROP 3 LASTPIN (-1150 1550) SIG_NAME M_F_CPU0_SB_DQ<7>
J 0
(-1140 1560);
DISPLAY 0.659574 (-1140 1560);
PAINT MONO (-1140 1560);
DISPLAY INVISIBLE (-1140 1560);
FORCEPROP 1 LASTPIN (-1150 1550) BN 7
J 0
(-1162 1558);
DISPLAY 0.680851 (-1162 1558);
PAINT GREEN (-1162 1558);
FORCEPROP 2 LAST CDS_LIB standard
J 0
(-1100 1550);
PAINT MONO (-1100 1550);
DISPLAY INVISIBLE (-1100 1550);
FORCEPROP 1 LAST BODY_TYPE PLUMBING
J 0
(-1100 1600);
DISPLAY 0.872340 (-1100 1600);
PAINT GREEN (-1100 1600);
DISPLAY INVISIBLE (-1100 1600);
FORCEPROP 1 LAST HDL_TAP TRUE
J 0
(-775 1425);
DISPLAY 0.872340 (-775 1425);
DISPLAY INVISIBLE (-775 1425);
FORCEPROP 1 LAST PATH I40
J 0
(-1102 1550);
DISPLAY 0.872340 (-1102 1550);
PAINT GREEN (-1102 1550);
DISPLAY INVISIBLE (-1102 1550);
FORCEADD TAP..1
(-1100 1750);
FORCEPROP 3 LASTPIN (-1150 1750) SIG_NAME M_F_CPU0_SB_DQ<11>
J 0
(-1140 1760);
DISPLAY 0.659574 (-1140 1760);
PAINT MONO (-1140 1760);
DISPLAY INVISIBLE (-1140 1760);
FORCEPROP 1 LASTPIN (-1150 1750) BN 11
J 0
(-1162 1758);
DISPLAY 0.680851 (-1162 1758);
PAINT GREEN (-1162 1758);
FORCEPROP 2 LAST CDS_LIB standard
J 0
(-1100 1750);
PAINT MONO (-1100 1750);
DISPLAY INVISIBLE (-1100 1750);
FORCEPROP 1 LAST BODY_TYPE PLUMBING
J 0
(-1100 1800);
DISPLAY 0.872340 (-1100 1800);
PAINT GREEN (-1100 1800);
DISPLAY INVISIBLE (-1100 1800);
FORCEPROP 1 LAST HDL_TAP TRUE
J 0
(-775 1625);
DISPLAY 0.872340 (-775 1625);
DISPLAY INVISIBLE (-775 1625);
FORCEPROP 1 LAST PATH I41
J 0
(-1102 1750);
DISPLAY 0.872340 (-1102 1750);
PAINT GREEN (-1102 1750);
DISPLAY INVISIBLE (-1102 1750);
FORCEADD TAP..1
(-1100 1700);
FORCEPROP 3 LASTPIN (-1150 1700) SIG_NAME M_F_CPU0_SB_DQ<10>
J 0
(-1140 1710);
DISPLAY 0.659574 (-1140 1710);
PAINT MONO (-1140 1710);
DISPLAY INVISIBLE (-1140 1710);
FORCEPROP 1 LASTPIN (-1150 1700) BN 10
J 0
(-1162 1708);
DISPLAY 0.680851 (-1162 1708);
PAINT GREEN (-1162 1708);
FORCEPROP 2 LAST CDS_LIB standard
J 0
(-1100 1700);
PAINT MONO (-1100 1700);
DISPLAY INVISIBLE (-1100 1700);
FORCEPROP 1 LAST BODY_TYPE PLUMBING
J 0
(-1100 1750);
DISPLAY 0.872340 (-1100 1750);
PAINT GREEN (-1100 1750);
DISPLAY INVISIBLE (-1100 1750);
FORCEPROP 1 LAST HDL_TAP TRUE
J 0
(-775 1575);
DISPLAY 0.872340 (-775 1575);
DISPLAY INVISIBLE (-775 1575);
FORCEPROP 1 LAST PATH I42
J 0
(-1102 1700);
DISPLAY 0.872340 (-1102 1700);
PAINT GREEN (-1102 1700);
DISPLAY INVISIBLE (-1102 1700);
FORCEADD TAP..1
(-1100 1900);
FORCEPROP 3 LASTPIN (-1150 1900) SIG_NAME M_F_CPU0_SB_DQ<14>
J 0
(-1140 1910);
DISPLAY 0.659574 (-1140 1910);
PAINT MONO (-1140 1910);
DISPLAY INVISIBLE (-1140 1910);
FORCEPROP 1 LASTPIN (-1150 1900) BN 14
J 0
(-1162 1908);
DISPLAY 0.680851 (-1162 1908);
PAINT GREEN (-1162 1908);
FORCEPROP 2 LAST CDS_LIB standard
J 0
(-1100 1900);
PAINT MONO (-1100 1900);
DISPLAY INVISIBLE (-1100 1900);
FORCEPROP 1 LAST BODY_TYPE PLUMBING
J 0
(-1100 1950);
DISPLAY 0.872340 (-1100 1950);
PAINT GREEN (-1100 1950);
DISPLAY INVISIBLE (-1100 1950);
FORCEPROP 1 LAST HDL_TAP TRUE
J 0
(-775 1775);
DISPLAY 0.872340 (-775 1775);
DISPLAY INVISIBLE (-775 1775);
FORCEPROP 1 LAST PATH I43
J 0
(-1102 1900);
DISPLAY 0.872340 (-1102 1900);
PAINT GREEN (-1102 1900);
DISPLAY INVISIBLE (-1102 1900);
FORCEADD TAP..1
(-1100 1850);
FORCEPROP 3 LASTPIN (-1150 1850) SIG_NAME M_F_CPU0_SB_DQ<13>
J 0
(-1140 1860);
DISPLAY 0.659574 (-1140 1860);
PAINT MONO (-1140 1860);
DISPLAY INVISIBLE (-1140 1860);
FORCEPROP 1 LASTPIN (-1150 1850) BN 13
J 0
(-1162 1858);
DISPLAY 0.680851 (-1162 1858);
PAINT GREEN (-1162 1858);
FORCEPROP 2 LAST CDS_LIB standard
J 0
(-1100 1850);
PAINT MONO (-1100 1850);
DISPLAY INVISIBLE (-1100 1850);
FORCEPROP 1 LAST BODY_TYPE PLUMBING
J 0
(-1100 1900);
DISPLAY 0.872340 (-1100 1900);
PAINT GREEN (-1100 1900);
DISPLAY INVISIBLE (-1100 1900);
FORCEPROP 1 LAST HDL_TAP TRUE
J 0
(-775 1725);
DISPLAY 0.872340 (-775 1725);
DISPLAY INVISIBLE (-775 1725);
FORCEPROP 1 LAST PATH I44
J 0
(-1102 1850);
DISPLAY 0.872340 (-1102 1850);
PAINT GREEN (-1102 1850);
DISPLAY INVISIBLE (-1102 1850);
FORCEADD TAP..1
(-1100 1800);
FORCEPROP 3 LASTPIN (-1150 1800) SIG_NAME M_F_CPU0_SB_DQ<12>
J 0
(-1140 1810);
DISPLAY 0.659574 (-1140 1810);
PAINT MONO (-1140 1810);
DISPLAY INVISIBLE (-1140 1810);
FORCEPROP 1 LASTPIN (-1150 1800) BN 12
J 0
(-1162 1808);
DISPLAY 0.680851 (-1162 1808);
PAINT GREEN (-1162 1808);
FORCEPROP 2 LAST CDS_LIB standard
J 0
(-1100 1800);
PAINT MONO (-1100 1800);
DISPLAY INVISIBLE (-1100 1800);
FORCEPROP 1 LAST BODY_TYPE PLUMBING
J 0
(-1100 1850);
DISPLAY 0.872340 (-1100 1850);
PAINT GREEN (-1100 1850);
DISPLAY INVISIBLE (-1100 1850);
FORCEPROP 1 LAST HDL_TAP TRUE
J 0
(-775 1675);
DISPLAY 0.872340 (-775 1675);
DISPLAY INVISIBLE (-775 1675);
FORCEPROP 1 LAST PATH I45
J 0
(-1102 1800);
DISPLAY 0.872340 (-1102 1800);
PAINT GREEN (-1102 1800);
DISPLAY INVISIBLE (-1102 1800);
FORCEADD TAP..1
(-1100 2000);
FORCEPROP 3 LASTPIN (-1150 2000) SIG_NAME M_F_CPU0_SB_DQ<16>
J 0
(-1140 2010);
DISPLAY 0.659574 (-1140 2010);
PAINT MONO (-1140 2010);
DISPLAY INVISIBLE (-1140 2010);
FORCEPROP 1 LASTPIN (-1150 2000) BN 16
J 0
(-1162 2008);
DISPLAY 0.680851 (-1162 2008);
PAINT GREEN (-1162 2008);
FORCEPROP 2 LAST CDS_LIB standard
J 0
(-1100 2000);
PAINT MONO (-1100 2000);
DISPLAY INVISIBLE (-1100 2000);
FORCEPROP 1 LAST BODY_TYPE PLUMBING
J 0
(-1100 2050);
DISPLAY 0.872340 (-1100 2050);
PAINT GREEN (-1100 2050);
DISPLAY INVISIBLE (-1100 2050);
FORCEPROP 1 LAST HDL_TAP TRUE
J 0
(-775 1875);
DISPLAY 0.872340 (-775 1875);
DISPLAY INVISIBLE (-775 1875);
FORCEPROP 1 LAST PATH I46
J 0
(-1102 2000);
DISPLAY 0.872340 (-1102 2000);
PAINT GREEN (-1102 2000);
DISPLAY INVISIBLE (-1102 2000);
FORCEADD TAP..1
(-1100 1950);
FORCEPROP 3 LASTPIN (-1150 1950) SIG_NAME M_F_CPU0_SB_DQ<15>
J 0
(-1140 1960);
DISPLAY 0.659574 (-1140 1960);
PAINT MONO (-1140 1960);
DISPLAY INVISIBLE (-1140 1960);
FORCEPROP 1 LASTPIN (-1150 1950) BN 15
J 0
(-1162 1958);
DISPLAY 0.680851 (-1162 1958);
PAINT GREEN (-1162 1958);
FORCEPROP 2 LAST CDS_LIB standard
J 0
(-1100 1950);
PAINT MONO (-1100 1950);
DISPLAY INVISIBLE (-1100 1950);
FORCEPROP 1 LAST BODY_TYPE PLUMBING
J 0
(-1100 2000);
DISPLAY 0.872340 (-1100 2000);
PAINT GREEN (-1100 2000);
DISPLAY INVISIBLE (-1100 2000);
FORCEPROP 1 LAST HDL_TAP TRUE
J 0
(-775 1825);
DISPLAY 0.872340 (-775 1825);
DISPLAY INVISIBLE (-775 1825);
FORCEPROP 1 LAST PATH I47
J 0
(-1102 1950);
DISPLAY 0.872340 (-1102 1950);
PAINT GREEN (-1102 1950);
DISPLAY INVISIBLE (-1102 1950);
FORCEADD TAP..1
(-1100 2150);
FORCEPROP 3 LASTPIN (-1150 2150) SIG_NAME M_F_CPU0_SB_DQ<19>
J 0
(-1140 2160);
DISPLAY 0.659574 (-1140 2160);
PAINT MONO (-1140 2160);
DISPLAY INVISIBLE (-1140 2160);
FORCEPROP 1 LASTPIN (-1150 2150) BN 19
J 0
(-1162 2158);
DISPLAY 0.680851 (-1162 2158);
PAINT GREEN (-1162 2158);
FORCEPROP 2 LAST CDS_LIB standard
J 0
(-1100 2150);
PAINT MONO (-1100 2150);
DISPLAY INVISIBLE (-1100 2150);
FORCEPROP 1 LAST BODY_TYPE PLUMBING
J 0
(-1100 2200);
DISPLAY 0.872340 (-1100 2200);
PAINT GREEN (-1100 2200);
DISPLAY INVISIBLE (-1100 2200);
FORCEPROP 1 LAST HDL_TAP TRUE
J 0
(-775 2025);
DISPLAY 0.872340 (-775 2025);
DISPLAY INVISIBLE (-775 2025);
FORCEPROP 1 LAST PATH I48
J 0
(-1102 2150);
DISPLAY 0.872340 (-1102 2150);
PAINT GREEN (-1102 2150);
DISPLAY INVISIBLE (-1102 2150);
FORCEADD TAP..1
(-1100 2100);
FORCEPROP 3 LASTPIN (-1150 2100) SIG_NAME M_F_CPU0_SB_DQ<18>
J 0
(-1140 2110);
DISPLAY 0.659574 (-1140 2110);
PAINT MONO (-1140 2110);
DISPLAY INVISIBLE (-1140 2110);
FORCEPROP 1 LASTPIN (-1150 2100) BN 18
J 0
(-1162 2108);
DISPLAY 0.680851 (-1162 2108);
PAINT GREEN (-1162 2108);
FORCEPROP 2 LAST CDS_LIB standard
J 0
(-1100 2100);
PAINT MONO (-1100 2100);
DISPLAY INVISIBLE (-1100 2100);
FORCEPROP 1 LAST BODY_TYPE PLUMBING
J 0
(-1100 2150);
DISPLAY 0.872340 (-1100 2150);
PAINT GREEN (-1100 2150);
DISPLAY INVISIBLE (-1100 2150);
FORCEPROP 1 LAST HDL_TAP TRUE
J 0
(-775 1975);
DISPLAY 0.872340 (-775 1975);
DISPLAY INVISIBLE (-775 1975);
FORCEPROP 1 LAST PATH I49
J 0
(-1102 2100);
DISPLAY 0.872340 (-1102 2100);
PAINT GREEN (-1102 2100);
DISPLAY INVISIBLE (-1102 2100);
FORCEADD OFFPAGE..2
R 2
(-3675 950);
FORCEPROP 2 LAST $XR0 25 
J 0
(-3899 950);
DISPLAY 0.638298 (-3899 950);
PAINT MONO (-3899 950);
FORCEPROP 2 LAST CDS_LIB standard
J 0
(-3675 950);
PAINT MONO (-3675 950);
DISPLAY INVISIBLE (-3675 950);
FORCEPROP 1 LAST OFFPAGE TRUE
J 2
(-4000 825);
DISPLAY 0.872340 (-4000 825);
DISPLAY INVISIBLE (-4000 825);
FORCEPROP 1 LAST COMMENT_BODY TRUE
J 2
(-3630 855);
DISPLAY 0.872340 (-3630 855);
PAINT GREEN (-3630 855);
DISPLAY INVISIBLE (-3630 855);
FORCEPROP 2 LAST PATH I5
J 0
(-3625 1025);
DISPLAY 1.021277 (-3625 1025);
DISPLAY INVISIBLE (-3625 1025);
FORCEADD TAP..1
(-1100 2050);
FORCEPROP 3 LASTPIN (-1150 2050) SIG_NAME M_F_CPU0_SB_DQ<17>
J 0
(-1140 2060);
DISPLAY 0.659574 (-1140 2060);
PAINT MONO (-1140 2060);
DISPLAY INVISIBLE (-1140 2060);
FORCEPROP 1 LASTPIN (-1150 2050) BN 17
J 0
(-1162 2058);
DISPLAY 0.680851 (-1162 2058);
PAINT GREEN (-1162 2058);
FORCEPROP 2 LAST CDS_LIB standard
J 0
(-1100 2050);
PAINT MONO (-1100 2050);
DISPLAY INVISIBLE (-1100 2050);
FORCEPROP 1 LAST BODY_TYPE PLUMBING
J 0
(-1100 2100);
DISPLAY 0.872340 (-1100 2100);
PAINT GREEN (-1100 2100);
DISPLAY INVISIBLE (-1100 2100);
FORCEPROP 1 LAST HDL_TAP TRUE
J 0
(-775 1925);
DISPLAY 0.872340 (-775 1925);
DISPLAY INVISIBLE (-775 1925);
FORCEPROP 1 LAST PATH I50
J 0
(-1102 2050);
DISPLAY 0.872340 (-1102 2050);
PAINT GREEN (-1102 2050);
DISPLAY INVISIBLE (-1102 2050);
FORCEADD TAP..1
(-1100 2200);
FORCEPROP 3 LASTPIN (-1150 2200) SIG_NAME M_F_CPU0_SB_DQ<20>
J 0
(-1140 2210);
DISPLAY 0.659574 (-1140 2210);
PAINT MONO (-1140 2210);
DISPLAY INVISIBLE (-1140 2210);
FORCEPROP 1 LASTPIN (-1150 2200) BN 20
J 0
(-1162 2208);
DISPLAY 0.680851 (-1162 2208);
PAINT GREEN (-1162 2208);
FORCEPROP 2 LAST CDS_LIB standard
J 0
(-1100 2200);
PAINT MONO (-1100 2200);
DISPLAY INVISIBLE (-1100 2200);
FORCEPROP 1 LAST BODY_TYPE PLUMBING
J 0
(-1100 2250);
DISPLAY 0.872340 (-1100 2250);
PAINT GREEN (-1100 2250);
DISPLAY INVISIBLE (-1100 2250);
FORCEPROP 1 LAST HDL_TAP TRUE
J 0
(-775 2075);
DISPLAY 0.872340 (-775 2075);
DISPLAY INVISIBLE (-775 2075);
FORCEPROP 1 LAST PATH I51
J 0
(-1102 2200);
DISPLAY 0.872340 (-1102 2200);
PAINT GREEN (-1102 2200);
DISPLAY INVISIBLE (-1102 2200);
FORCEADD TAP..1
(-1100 2250);
FORCEPROP 3 LASTPIN (-1150 2250) SIG_NAME M_F_CPU0_SB_DQ<21>
J 0
(-1140 2260);
DISPLAY 0.659574 (-1140 2260);
PAINT MONO (-1140 2260);
DISPLAY INVISIBLE (-1140 2260);
FORCEPROP 1 LASTPIN (-1150 2250) BN 21
J 0
(-1162 2258);
DISPLAY 0.680851 (-1162 2258);
PAINT GREEN (-1162 2258);
FORCEPROP 2 LAST CDS_LIB standard
J 0
(-1100 2250);
PAINT MONO (-1100 2250);
DISPLAY INVISIBLE (-1100 2250);
FORCEPROP 1 LAST BODY_TYPE PLUMBING
J 0
(-1100 2300);
DISPLAY 0.872340 (-1100 2300);
PAINT GREEN (-1100 2300);
DISPLAY INVISIBLE (-1100 2300);
FORCEPROP 1 LAST HDL_TAP TRUE
J 0
(-775 2125);
DISPLAY 0.872340 (-775 2125);
DISPLAY INVISIBLE (-775 2125);
FORCEPROP 1 LAST PATH I52
J 0
(-1102 2250);
DISPLAY 0.872340 (-1102 2250);
PAINT GREEN (-1102 2250);
DISPLAY INVISIBLE (-1102 2250);
FORCEADD TAP..1
(-1100 2300);
FORCEPROP 3 LASTPIN (-1150 2300) SIG_NAME M_F_CPU0_SB_DQ<22>
J 0
(-1140 2310);
DISPLAY 0.659574 (-1140 2310);
PAINT MONO (-1140 2310);
DISPLAY INVISIBLE (-1140 2310);
FORCEPROP 1 LASTPIN (-1150 2300) BN 22
J 0
(-1162 2308);
DISPLAY 0.680851 (-1162 2308);
PAINT GREEN (-1162 2308);
FORCEPROP 2 LAST CDS_LIB standard
J 0
(-1100 2300);
DISPLAY INVISIBLE (-1100 2300);
FORCEPROP 1 LAST BODY_TYPE PLUMBING
J 0
(-1100 2350);
DISPLAY 0.872340 (-1100 2350);
PAINT GREEN (-1100 2350);
DISPLAY INVISIBLE (-1100 2350);
FORCEPROP 1 LAST HDL_TAP TRUE
J 0
(-775 2175);
DISPLAY 0.872340 (-775 2175);
DISPLAY INVISIBLE (-775 2175);
FORCEPROP 1 LAST PATH I53
J 0
(-1102 2300);
DISPLAY 0.872340 (-1102 2300);
PAINT GREEN (-1102 2300);
DISPLAY INVISIBLE (-1102 2300);
FORCEADD TAP..1
(-1100 2400);
FORCEPROP 3 LASTPIN (-1150 2400) SIG_NAME M_F_CPU0_SB_DQ<24>
J 0
(-1140 2410);
DISPLAY 0.659574 (-1140 2410);
PAINT MONO (-1140 2410);
DISPLAY INVISIBLE (-1140 2410);
FORCEPROP 1 LASTPIN (-1150 2400) BN 24
J 0
(-1162 2408);
DISPLAY 0.680851 (-1162 2408);
PAINT GREEN (-1162 2408);
FORCEPROP 2 LAST CDS_LIB standard
J 0
(-1100 2400);
DISPLAY INVISIBLE (-1100 2400);
FORCEPROP 1 LAST BODY_TYPE PLUMBING
J 0
(-1100 2450);
DISPLAY 0.872340 (-1100 2450);
PAINT GREEN (-1100 2450);
DISPLAY INVISIBLE (-1100 2450);
FORCEPROP 1 LAST HDL_TAP TRUE
J 0
(-775 2275);
DISPLAY 0.872340 (-775 2275);
DISPLAY INVISIBLE (-775 2275);
FORCEPROP 1 LAST PATH I54
J 0
(-1102 2400);
DISPLAY 0.872340 (-1102 2400);
PAINT GREEN (-1102 2400);
DISPLAY INVISIBLE (-1102 2400);
FORCEADD TAP..1
(-1100 2350);
FORCEPROP 3 LASTPIN (-1150 2350) SIG_NAME M_F_CPU0_SB_DQ<23>
J 0
(-1140 2360);
DISPLAY 0.659574 (-1140 2360);
PAINT MONO (-1140 2360);
DISPLAY INVISIBLE (-1140 2360);
FORCEPROP 1 LASTPIN (-1150 2350) BN 23
J 0
(-1162 2358);
DISPLAY 0.680851 (-1162 2358);
PAINT GREEN (-1162 2358);
FORCEPROP 2 LAST CDS_LIB standard
J 0
(-1100 2350);
DISPLAY INVISIBLE (-1100 2350);
FORCEPROP 1 LAST BODY_TYPE PLUMBING
J 0
(-1100 2400);
DISPLAY 0.872340 (-1100 2400);
PAINT GREEN (-1100 2400);
DISPLAY INVISIBLE (-1100 2400);
FORCEPROP 1 LAST HDL_TAP TRUE
J 0
(-775 2225);
DISPLAY 0.872340 (-775 2225);
DISPLAY INVISIBLE (-775 2225);
FORCEPROP 1 LAST PATH I55
J 0
(-1102 2350);
DISPLAY 0.872340 (-1102 2350);
PAINT GREEN (-1102 2350);
DISPLAY INVISIBLE (-1102 2350);
FORCEADD TAP..1
R 2
(-2750 2500);
FORCEPROP 3 LASTPIN (-2700 2500) SIG_NAME M_F_CPU0_SB_CB<6>
J 0
(-2690 2510);
DISPLAY 0.659574 (-2690 2510);
PAINT MONO (-2690 2510);
DISPLAY INVISIBLE (-2690 2510);
FORCEPROP 1 LASTPIN (-2700 2500) BN 6
J 2
(-2688 2508);
DISPLAY 0.680851 (-2688 2508);
PAINT GREEN (-2688 2508);
FORCEPROP 2 LAST CDS_LIB standard
J 0
(-2750 2500);
DISPLAY INVISIBLE (-2750 2500);
FORCEPROP 1 LAST BODY_TYPE PLUMBING
J 2
(-2750 2550);
DISPLAY 0.872340 (-2750 2550);
PAINT GREEN (-2750 2550);
DISPLAY INVISIBLE (-2750 2550);
FORCEPROP 1 LAST HDL_TAP TRUE
J 2
(-3075 2375);
DISPLAY 0.872340 (-3075 2375);
DISPLAY INVISIBLE (-3075 2375);
FORCEPROP 1 LAST PATH I56
J 2
(-2748 2500);
DISPLAY 0.872340 (-2748 2500);
PAINT GREEN (-2748 2500);
DISPLAY INVISIBLE (-2748 2500);
FORCEADD TAP..1
R 2
(-2750 2450);
FORCEPROP 3 LASTPIN (-2700 2450) SIG_NAME M_F_CPU0_SB_CB<5>
J 0
(-2690 2460);
DISPLAY 0.659574 (-2690 2460);
PAINT MONO (-2690 2460);
DISPLAY INVISIBLE (-2690 2460);
FORCEPROP 1 LASTPIN (-2700 2450) BN 5
J 2
(-2688 2458);
DISPLAY 0.680851 (-2688 2458);
PAINT GREEN (-2688 2458);
FORCEPROP 2 LAST CDS_LIB standard
J 0
(-2750 2450);
DISPLAY INVISIBLE (-2750 2450);
FORCEPROP 1 LAST BODY_TYPE PLUMBING
J 2
(-2750 2500);
DISPLAY 0.872340 (-2750 2500);
PAINT GREEN (-2750 2500);
DISPLAY INVISIBLE (-2750 2500);
FORCEPROP 1 LAST HDL_TAP TRUE
J 2
(-3075 2325);
DISPLAY 0.872340 (-3075 2325);
DISPLAY INVISIBLE (-3075 2325);
FORCEPROP 1 LAST PATH I57
J 2
(-2748 2450);
DISPLAY 0.872340 (-2748 2450);
PAINT GREEN (-2748 2450);
DISPLAY INVISIBLE (-2748 2450);
FORCEADD TAP..1
R 2
(-2750 2650);
FORCEPROP 3 LASTPIN (-2700 2650) SIG_NAME M_F_CPU0_SA_CB<0>
J 0
(-2690 2660);
DISPLAY 0.659574 (-2690 2660);
PAINT MONO (-2690 2660);
DISPLAY INVISIBLE (-2690 2660);
FORCEPROP 1 LASTPIN (-2700 2650) BN 0
J 2
(-2688 2658);
DISPLAY 0.680851 (-2688 2658);
PAINT GREEN (-2688 2658);
FORCEPROP 2 LAST CDS_LIB standard
J 0
(-2750 2650);
PAINT MONO (-2750 2650);
DISPLAY INVISIBLE (-2750 2650);
FORCEPROP 1 LAST BODY_TYPE PLUMBING
J 2
(-2750 2700);
DISPLAY 0.872340 (-2750 2700);
PAINT GREEN (-2750 2700);
DISPLAY INVISIBLE (-2750 2700);
FORCEPROP 1 LAST HDL_TAP TRUE
J 2
(-3075 2525);
DISPLAY 0.872340 (-3075 2525);
DISPLAY INVISIBLE (-3075 2525);
FORCEPROP 1 LAST PATH I58
J 2
(-2748 2650);
DISPLAY 0.872340 (-2748 2650);
PAINT GREEN (-2748 2650);
DISPLAY INVISIBLE (-2748 2650);
FORCEADD TAP..1
R 2
(-2750 2550);
FORCEPROP 3 LASTPIN (-2700 2550) SIG_NAME M_F_CPU0_SB_CB<7>
J 0
(-2690 2560);
DISPLAY 0.659574 (-2690 2560);
PAINT MONO (-2690 2560);
DISPLAY INVISIBLE (-2690 2560);
FORCEPROP 1 LASTPIN (-2700 2550) BN 7
J 2
(-2688 2558);
DISPLAY 0.680851 (-2688 2558);
PAINT GREEN (-2688 2558);
FORCEPROP 2 LAST CDS_LIB standard
J 0
(-2750 2550);
DISPLAY INVISIBLE (-2750 2550);
FORCEPROP 1 LAST BODY_TYPE PLUMBING
J 2
(-2750 2600);
DISPLAY 0.872340 (-2750 2600);
PAINT GREEN (-2750 2600);
DISPLAY INVISIBLE (-2750 2600);
FORCEPROP 1 LAST HDL_TAP TRUE
J 2
(-3075 2425);
DISPLAY 0.872340 (-3075 2425);
DISPLAY INVISIBLE (-3075 2425);
FORCEPROP 1 LAST PATH I59
J 2
(-2748 2550);
DISPLAY 0.872340 (-2748 2550);
PAINT GREEN (-2748 2550);
DISPLAY INVISIBLE (-2748 2550);
FORCEADD OFFPAGE..3
R 2
(-3675 1550);
FORCEPROP 2 LAST $XR0 114 
J 0
(-3955 1550);
DISPLAY 0.638298 (-3955 1550);
PAINT MONO (-3955 1550);
FORCEPROP 2 LAST CDS_LIB standard
J 0
(-3675 1550);
PAINT MONO (-3675 1550);
DISPLAY INVISIBLE (-3675 1550);
FORCEPROP 1 LAST OFFPAGE TRUE
J 2
(-4000 1425);
DISPLAY 0.872340 (-4000 1425);
DISPLAY INVISIBLE (-4000 1425);
FORCEPROP 1 LAST COMMENT_BODY TRUE
J 2
(-3625 1450);
DISPLAY 0.872340 (-3625 1450);
PAINT GREEN (-3625 1450);
DISPLAY INVISIBLE (-3625 1450);
FORCEPROP 2 LAST PATH I6
J 0
(-3625 1625);
DISPLAY 1.021277 (-3625 1625);
DISPLAY INVISIBLE (-3625 1625);
FORCEADD TAP..1
R 2
(-2750 2700);
FORCEPROP 3 LASTPIN (-2700 2700) SIG_NAME M_F_CPU0_SA_CB<1>
J 0
(-2690 2710);
DISPLAY 0.659574 (-2690 2710);
PAINT MONO (-2690 2710);
DISPLAY INVISIBLE (-2690 2710);
FORCEPROP 1 LASTPIN (-2700 2700) BN 1
J 2
(-2688 2708);
DISPLAY 0.680851 (-2688 2708);
PAINT GREEN (-2688 2708);
FORCEPROP 2 LAST CDS_LIB standard
J 0
(-2750 2700);
DISPLAY INVISIBLE (-2750 2700);
FORCEPROP 1 LAST BODY_TYPE PLUMBING
J 2
(-2750 2750);
DISPLAY 0.872340 (-2750 2750);
PAINT GREEN (-2750 2750);
DISPLAY INVISIBLE (-2750 2750);
FORCEPROP 1 LAST HDL_TAP TRUE
J 2
(-3075 2575);
DISPLAY 0.872340 (-3075 2575);
DISPLAY INVISIBLE (-3075 2575);
FORCEPROP 1 LAST PATH I60
J 2
(-2748 2700);
DISPLAY 0.872340 (-2748 2700);
PAINT GREEN (-2748 2700);
DISPLAY INVISIBLE (-2748 2700);
FORCEADD TAP..1
R 2
(-2750 2750);
FORCEPROP 3 LASTPIN (-2700 2750) SIG_NAME M_F_CPU0_SA_CB<2>
J 0
(-2690 2760);
DISPLAY 0.659574 (-2690 2760);
PAINT MONO (-2690 2760);
DISPLAY INVISIBLE (-2690 2760);
FORCEPROP 1 LASTPIN (-2700 2750) BN 2
J 2
(-2688 2758);
DISPLAY 0.680851 (-2688 2758);
PAINT GREEN (-2688 2758);
FORCEPROP 2 LAST CDS_LIB standard
J 0
(-2750 2750);
DISPLAY INVISIBLE (-2750 2750);
FORCEPROP 1 LAST BODY_TYPE PLUMBING
J 2
(-2750 2800);
DISPLAY 0.872340 (-2750 2800);
PAINT GREEN (-2750 2800);
DISPLAY INVISIBLE (-2750 2800);
FORCEPROP 1 LAST HDL_TAP TRUE
J 2
(-3075 2625);
DISPLAY 0.872340 (-3075 2625);
DISPLAY INVISIBLE (-3075 2625);
FORCEPROP 1 LAST PATH I61
J 2
(-2748 2750);
DISPLAY 0.872340 (-2748 2750);
PAINT GREEN (-2748 2750);
DISPLAY INVISIBLE (-2748 2750);
FORCEADD TAP..1
R 2
(-2750 2800);
FORCEPROP 3 LASTPIN (-2700 2800) SIG_NAME M_F_CPU0_SA_CB<3>
J 0
(-2690 2810);
DISPLAY 0.659574 (-2690 2810);
PAINT MONO (-2690 2810);
DISPLAY INVISIBLE (-2690 2810);
FORCEPROP 1 LASTPIN (-2700 2800) BN 3
J 2
(-2688 2808);
DISPLAY 0.680851 (-2688 2808);
PAINT GREEN (-2688 2808);
FORCEPROP 2 LAST CDS_LIB standard
J 0
(-2750 2800);
DISPLAY INVISIBLE (-2750 2800);
FORCEPROP 1 LAST BODY_TYPE PLUMBING
J 2
(-2750 2850);
DISPLAY 0.872340 (-2750 2850);
PAINT GREEN (-2750 2850);
DISPLAY INVISIBLE (-2750 2850);
FORCEPROP 1 LAST HDL_TAP TRUE
J 2
(-3075 2675);
DISPLAY 0.872340 (-3075 2675);
DISPLAY INVISIBLE (-3075 2675);
FORCEPROP 1 LAST PATH I62
J 2
(-2748 2800);
DISPLAY 0.872340 (-2748 2800);
PAINT GREEN (-2748 2800);
DISPLAY INVISIBLE (-2748 2800);
FORCEADD TAP..1
R 2
(-2750 2900);
FORCEPROP 3 LASTPIN (-2700 2900) SIG_NAME M_F_CPU0_SA_CB<5>
J 0
(-2690 2910);
DISPLAY 0.659574 (-2690 2910);
PAINT MONO (-2690 2910);
DISPLAY INVISIBLE (-2690 2910);
FORCEPROP 1 LASTPIN (-2700 2900) BN 5
J 2
(-2688 2908);
DISPLAY 0.680851 (-2688 2908);
PAINT GREEN (-2688 2908);
FORCEPROP 2 LAST CDS_LIB standard
J 0
(-2750 2900);
DISPLAY INVISIBLE (-2750 2900);
FORCEPROP 1 LAST BODY_TYPE PLUMBING
J 2
(-2750 2950);
DISPLAY 0.872340 (-2750 2950);
PAINT GREEN (-2750 2950);
DISPLAY INVISIBLE (-2750 2950);
FORCEPROP 1 LAST HDL_TAP TRUE
J 2
(-3075 2775);
DISPLAY 0.872340 (-3075 2775);
DISPLAY INVISIBLE (-3075 2775);
FORCEPROP 1 LAST PATH I63
J 2
(-2748 2900);
DISPLAY 0.872340 (-2748 2900);
PAINT GREEN (-2748 2900);
DISPLAY INVISIBLE (-2748 2900);
FORCEADD TAP..1
R 2
(-2750 2850);
FORCEPROP 3 LASTPIN (-2700 2850) SIG_NAME M_F_CPU0_SA_CB<4>
J 0
(-2690 2860);
DISPLAY 0.659574 (-2690 2860);
PAINT MONO (-2690 2860);
DISPLAY INVISIBLE (-2690 2860);
FORCEPROP 1 LASTPIN (-2700 2850) BN 4
J 2
(-2688 2858);
DISPLAY 0.680851 (-2688 2858);
PAINT GREEN (-2688 2858);
FORCEPROP 2 LAST CDS_LIB standard
J 0
(-2750 2850);
DISPLAY INVISIBLE (-2750 2850);
FORCEPROP 1 LAST BODY_TYPE PLUMBING
J 2
(-2750 2900);
DISPLAY 0.872340 (-2750 2900);
PAINT GREEN (-2750 2900);
DISPLAY INVISIBLE (-2750 2900);
FORCEPROP 1 LAST HDL_TAP TRUE
J 2
(-3075 2725);
DISPLAY 0.872340 (-3075 2725);
DISPLAY INVISIBLE (-3075 2725);
FORCEPROP 1 LAST PATH I64
J 2
(-2748 2850);
DISPLAY 0.872340 (-2748 2850);
PAINT GREEN (-2748 2850);
DISPLAY INVISIBLE (-2748 2850);
FORCEADD TAP..1
R 2
(-2750 3000);
FORCEPROP 3 LASTPIN (-2700 3000) SIG_NAME M_F_CPU0_SA_CB<7>
J 0
(-2690 3010);
DISPLAY 0.659574 (-2690 3010);
PAINT MONO (-2690 3010);
DISPLAY INVISIBLE (-2690 3010);
FORCEPROP 1 LASTPIN (-2700 3000) BN 7
J 2
(-2688 3008);
DISPLAY 0.680851 (-2688 3008);
PAINT GREEN (-2688 3008);
FORCEPROP 2 LAST CDS_LIB standard
J 0
(-2750 3000);
DISPLAY INVISIBLE (-2750 3000);
FORCEPROP 1 LAST BODY_TYPE PLUMBING
J 2
(-2750 3050);
DISPLAY 0.872340 (-2750 3050);
PAINT GREEN (-2750 3050);
DISPLAY INVISIBLE (-2750 3050);
FORCEPROP 1 LAST HDL_TAP TRUE
J 2
(-3075 2875);
DISPLAY 0.872340 (-3075 2875);
DISPLAY INVISIBLE (-3075 2875);
FORCEPROP 1 LAST PATH I65
J 2
(-2748 3000);
DISPLAY 0.872340 (-2748 3000);
PAINT GREEN (-2748 3000);
DISPLAY INVISIBLE (-2748 3000);
FORCEADD TAP..1
R 2
(-2750 2950);
FORCEPROP 3 LASTPIN (-2700 2950) SIG_NAME M_F_CPU0_SA_CB<6>
J 0
(-2690 2960);
DISPLAY 0.659574 (-2690 2960);
PAINT MONO (-2690 2960);
DISPLAY INVISIBLE (-2690 2960);
FORCEPROP 1 LASTPIN (-2700 2950) BN 6
J 2
(-2688 2958);
DISPLAY 0.680851 (-2688 2958);
PAINT GREEN (-2688 2958);
FORCEPROP 2 LAST CDS_LIB standard
J 0
(-2750 2950);
DISPLAY INVISIBLE (-2750 2950);
FORCEPROP 1 LAST BODY_TYPE PLUMBING
J 2
(-2750 3000);
DISPLAY 0.872340 (-2750 3000);
PAINT GREEN (-2750 3000);
DISPLAY INVISIBLE (-2750 3000);
FORCEPROP 1 LAST HDL_TAP TRUE
J 2
(-3075 2825);
DISPLAY 0.872340 (-3075 2825);
DISPLAY INVISIBLE (-3075 2825);
FORCEPROP 1 LAST PATH I66
J 2
(-2748 2950);
DISPLAY 0.872340 (-2748 2950);
PAINT GREEN (-2748 2950);
DISPLAY INVISIBLE (-2748 2950);
FORCEADD TAP..1
R 2
(-2750 3700);
FORCEPROP 3 LASTPIN (-2700 3700) SIG_NAME M_F_CPU0_SB_CA<0>
J 0
(-2690 3710);
DISPLAY 0.659574 (-2690 3710);
PAINT MONO (-2690 3710);
DISPLAY INVISIBLE (-2690 3710);
FORCEPROP 1 LASTPIN (-2700 3700) BN 0
J 2
(-2688 3708);
DISPLAY 0.680851 (-2688 3708);
PAINT GREEN (-2688 3708);
FORCEPROP 2 LAST CDS_LIB standard
J 0
(-2750 3700);
DISPLAY INVISIBLE (-2750 3700);
FORCEPROP 1 LAST BODY_TYPE PLUMBING
J 2
(-2750 3750);
DISPLAY 0.872340 (-2750 3750);
PAINT GREEN (-2750 3750);
DISPLAY INVISIBLE (-2750 3750);
FORCEPROP 1 LAST HDL_TAP TRUE
J 2
(-3075 3575);
DISPLAY 0.872340 (-3075 3575);
DISPLAY INVISIBLE (-3075 3575);
FORCEPROP 1 LAST PATH I67
J 2
(-2748 3700);
DISPLAY 0.872340 (-2748 3700);
PAINT GREEN (-2748 3700);
DISPLAY INVISIBLE (-2748 3700);
FORCEADD TAP..1
R 2
(-2750 3750);
FORCEPROP 3 LASTPIN (-2700 3750) SIG_NAME M_F_CPU0_SB_CA<1>
J 0
(-2690 3760);
DISPLAY 0.659574 (-2690 3760);
PAINT MONO (-2690 3760);
DISPLAY INVISIBLE (-2690 3760);
FORCEPROP 1 LASTPIN (-2700 3750) BN 1
J 2
(-2688 3758);
DISPLAY 0.680851 (-2688 3758);
PAINT GREEN (-2688 3758);
FORCEPROP 2 LAST CDS_LIB standard
J 0
(-2750 3750);
DISPLAY INVISIBLE (-2750 3750);
FORCEPROP 1 LAST BODY_TYPE PLUMBING
J 2
(-2750 3800);
DISPLAY 0.872340 (-2750 3800);
PAINT GREEN (-2750 3800);
DISPLAY INVISIBLE (-2750 3800);
FORCEPROP 1 LAST HDL_TAP TRUE
J 2
(-3075 3625);
DISPLAY 0.872340 (-3075 3625);
DISPLAY INVISIBLE (-3075 3625);
FORCEPROP 1 LAST PATH I68
J 2
(-2748 3750);
DISPLAY 0.872340 (-2748 3750);
PAINT GREEN (-2748 3750);
DISPLAY INVISIBLE (-2748 3750);
FORCEADD TAP..1
R 2
(-2750 3800);
FORCEPROP 3 LASTPIN (-2700 3800) SIG_NAME M_F_CPU0_SB_CA<2>
J 0
(-2690 3810);
DISPLAY 0.659574 (-2690 3810);
PAINT MONO (-2690 3810);
DISPLAY INVISIBLE (-2690 3810);
FORCEPROP 1 LASTPIN (-2700 3800) BN 2
J 2
(-2688 3808);
DISPLAY 0.680851 (-2688 3808);
PAINT GREEN (-2688 3808);
FORCEPROP 2 LAST CDS_LIB standard
J 0
(-2750 3800);
DISPLAY INVISIBLE (-2750 3800);
FORCEPROP 1 LAST BODY_TYPE PLUMBING
J 2
(-2750 3850);
DISPLAY 0.872340 (-2750 3850);
PAINT GREEN (-2750 3850);
DISPLAY INVISIBLE (-2750 3850);
FORCEPROP 1 LAST HDL_TAP TRUE
J 2
(-3075 3675);
DISPLAY 0.872340 (-3075 3675);
DISPLAY INVISIBLE (-3075 3675);
FORCEPROP 1 LAST PATH I69
J 2
(-2748 3800);
DISPLAY 0.872340 (-2748 3800);
PAINT GREEN (-2748 3800);
DISPLAY INVISIBLE (-2748 3800);
FORCEADD OFFPAGE..1
(-3600 1850);
FORCEPROP 2 LAST $XR7 97 
J 0
(-3972 1886);
DISPLAY 0.638298 (-3972 1886);
PAINT MONO (-3972 1886);
FORCEPROP 2 LAST $XR6 96 
J 0
(-3882 1886);
DISPLAY 0.638298 (-3882 1886);
PAINT MONO (-3882 1886);
FORCEPROP 2 LAST $XR5 95 
J 0
(-4062 1814);
DISPLAY 0.638298 (-4062 1814);
PAINT MONO (-4062 1814);
FORCEPROP 2 LAST $XR4 94 
J 0
(-3972 1814);
DISPLAY 0.638298 (-3972 1814);
PAINT MONO (-3972 1814);
FORCEPROP 2 LAST $XR3 93 
J 0
(-3882 1814);
DISPLAY 0.638298 (-3882 1814);
PAINT MONO (-3882 1814);
FORCEPROP 2 LAST $XR2 91 
J 0
(-4062 1850);
DISPLAY 0.638298 (-4062 1850);
PAINT MONO (-4062 1850);
FORCEPROP 2 LAST $XR1 90 
J 0
(-3972 1850);
DISPLAY 0.638298 (-3972 1850);
PAINT MONO (-3972 1850);
FORCEPROP 2 LAST $XR0 229 
J 0
(-3882 1850);
DISPLAY 0.638298 (-3882 1850);
PAINT MONO (-3882 1850);
FORCEPROP 2 LAST CDS_LIB standard
J 0
(-3600 1850);
PAINT MONO (-3600 1850);
DISPLAY INVISIBLE (-3600 1850);
FORCEPROP 1 LAST OFFPAGE TRUE
J 0
(-3275 1725);
DISPLAY 0.872340 (-3275 1725);
DISPLAY INVISIBLE (-3275 1725);
FORCEPROP 1 LAST COMMENT_BODY TRUE
J 0
(-3475 1750);
DISPLAY 0.872340 (-3475 1750);
PAINT GREEN (-3475 1750);
DISPLAY INVISIBLE (-3475 1750);
FORCEPROP 2 LAST PATH I7
J 0
(-3550 1925);
DISPLAY 1.021277 (-3550 1925);
DISPLAY INVISIBLE (-3550 1925);
FORCEADD TAP..1
R 2
(-2750 3850);
FORCEPROP 3 LASTPIN (-2700 3850) SIG_NAME M_F_CPU0_SB_CA<3>
J 0
(-2690 3860);
DISPLAY 0.659574 (-2690 3860);
PAINT MONO (-2690 3860);
DISPLAY INVISIBLE (-2690 3860);
FORCEPROP 1 LASTPIN (-2700 3850) BN 3
J 2
(-2688 3858);
DISPLAY 0.680851 (-2688 3858);
PAINT GREEN (-2688 3858);
FORCEPROP 2 LAST CDS_LIB standard
J 0
(-2750 3850);
DISPLAY INVISIBLE (-2750 3850);
FORCEPROP 1 LAST BODY_TYPE PLUMBING
J 2
(-2750 3900);
DISPLAY 0.872340 (-2750 3900);
PAINT GREEN (-2750 3900);
DISPLAY INVISIBLE (-2750 3900);
FORCEPROP 1 LAST HDL_TAP TRUE
J 2
(-3075 3725);
DISPLAY 0.872340 (-3075 3725);
DISPLAY INVISIBLE (-3075 3725);
FORCEPROP 1 LAST PATH I70
J 2
(-2748 3850);
DISPLAY 0.872340 (-2748 3850);
PAINT GREEN (-2748 3850);
DISPLAY INVISIBLE (-2748 3850);
FORCEADD TAP..1
R 2
(-2750 3900);
FORCEPROP 3 LASTPIN (-2700 3900) SIG_NAME M_F_CPU0_SB_CA<4>
J 0
(-2690 3910);
DISPLAY 0.659574 (-2690 3910);
PAINT MONO (-2690 3910);
DISPLAY INVISIBLE (-2690 3910);
FORCEPROP 1 LASTPIN (-2700 3900) BN 4
J 2
(-2688 3908);
DISPLAY 0.680851 (-2688 3908);
PAINT GREEN (-2688 3908);
FORCEPROP 2 LAST CDS_LIB standard
J 0
(-2750 3900);
DISPLAY INVISIBLE (-2750 3900);
FORCEPROP 1 LAST BODY_TYPE PLUMBING
J 2
(-2750 3950);
DISPLAY 0.872340 (-2750 3950);
PAINT GREEN (-2750 3950);
DISPLAY INVISIBLE (-2750 3950);
FORCEPROP 1 LAST HDL_TAP TRUE
J 2
(-3075 3775);
DISPLAY 0.872340 (-3075 3775);
DISPLAY INVISIBLE (-3075 3775);
FORCEPROP 1 LAST PATH I71
J 2
(-2748 3900);
DISPLAY 0.872340 (-2748 3900);
PAINT GREEN (-2748 3900);
DISPLAY INVISIBLE (-2748 3900);
FORCEADD TAP..1
R 2
(-2750 3950);
FORCEPROP 3 LASTPIN (-2700 3950) SIG_NAME M_F_CPU0_SB_CA<5>
J 0
(-2690 3960);
DISPLAY 0.659574 (-2690 3960);
PAINT MONO (-2690 3960);
DISPLAY INVISIBLE (-2690 3960);
FORCEPROP 1 LASTPIN (-2700 3950) BN 5
J 2
(-2688 3958);
DISPLAY 0.680851 (-2688 3958);
PAINT GREEN (-2688 3958);
FORCEPROP 2 LAST CDS_LIB standard
J 0
(-2750 3950);
DISPLAY INVISIBLE (-2750 3950);
FORCEPROP 1 LAST BODY_TYPE PLUMBING
J 2
(-2750 4000);
DISPLAY 0.872340 (-2750 4000);
PAINT GREEN (-2750 4000);
DISPLAY INVISIBLE (-2750 4000);
FORCEPROP 1 LAST HDL_TAP TRUE
J 2
(-3075 3825);
DISPLAY 0.872340 (-3075 3825);
DISPLAY INVISIBLE (-3075 3825);
FORCEPROP 1 LAST PATH I72
J 2
(-2748 3950);
DISPLAY 0.872340 (-2748 3950);
PAINT GREEN (-2748 3950);
DISPLAY INVISIBLE (-2748 3950);
FORCEADD TAP..1
R 2
(-2750 4000);
FORCEPROP 3 LASTPIN (-2700 4000) SIG_NAME M_F_CPU0_SB_CA<6>
J 0
(-2690 4010);
DISPLAY 0.659574 (-2690 4010);
PAINT MONO (-2690 4010);
DISPLAY INVISIBLE (-2690 4010);
FORCEPROP 1 LASTPIN (-2700 4000) BN 6
J 2
(-2688 4008);
DISPLAY 0.680851 (-2688 4008);
PAINT GREEN (-2688 4008);
FORCEPROP 2 LAST CDS_LIB standard
J 0
(-2750 4000);
DISPLAY INVISIBLE (-2750 4000);
FORCEPROP 1 LAST BODY_TYPE PLUMBING
J 2
(-2750 4050);
DISPLAY 0.872340 (-2750 4050);
PAINT GREEN (-2750 4050);
DISPLAY INVISIBLE (-2750 4050);
FORCEPROP 1 LAST HDL_TAP TRUE
J 2
(-3075 3875);
DISPLAY 0.872340 (-3075 3875);
DISPLAY INVISIBLE (-3075 3875);
FORCEPROP 1 LAST PATH I73
J 2
(-2748 4000);
DISPLAY 0.872340 (-2748 4000);
PAINT GREEN (-2748 4000);
DISPLAY INVISIBLE (-2748 4000);
FORCEADD TAP..1
R 2
(-2750 4150);
FORCEPROP 3 LASTPIN (-2700 4150) SIG_NAME M_F_CPU0_SA_CA<1>
J 0
(-2690 4160);
DISPLAY 0.659574 (-2690 4160);
PAINT MONO (-2690 4160);
DISPLAY INVISIBLE (-2690 4160);
FORCEPROP 1 LASTPIN (-2700 4150) BN 1
J 2
(-2688 4158);
DISPLAY 0.680851 (-2688 4158);
PAINT GREEN (-2688 4158);
FORCEPROP 2 LAST CDS_LIB standard
J 0
(-2750 4150);
DISPLAY INVISIBLE (-2750 4150);
FORCEPROP 1 LAST BODY_TYPE PLUMBING
J 2
(-2750 4200);
DISPLAY 0.872340 (-2750 4200);
PAINT GREEN (-2750 4200);
DISPLAY INVISIBLE (-2750 4200);
FORCEPROP 1 LAST HDL_TAP TRUE
J 2
(-3075 4025);
DISPLAY 0.872340 (-3075 4025);
DISPLAY INVISIBLE (-3075 4025);
FORCEPROP 1 LAST PATH I74
J 2
(-2748 4150);
DISPLAY 0.872340 (-2748 4150);
PAINT GREEN (-2748 4150);
DISPLAY INVISIBLE (-2748 4150);
FORCEADD TAP..1
R 2
(-2750 4100);
FORCEPROP 3 LASTPIN (-2700 4100) SIG_NAME M_F_CPU0_SA_CA<0>
J 0
(-2690 4110);
DISPLAY 0.659574 (-2690 4110);
PAINT MONO (-2690 4110);
DISPLAY INVISIBLE (-2690 4110);
FORCEPROP 1 LASTPIN (-2700 4100) BN 0
J 2
(-2688 4108);
DISPLAY 0.680851 (-2688 4108);
PAINT GREEN (-2688 4108);
FORCEPROP 2 LAST CDS_LIB standard
J 0
(-2750 4100);
DISPLAY INVISIBLE (-2750 4100);
FORCEPROP 1 LAST BODY_TYPE PLUMBING
J 2
(-2750 4150);
DISPLAY 0.872340 (-2750 4150);
PAINT GREEN (-2750 4150);
DISPLAY INVISIBLE (-2750 4150);
FORCEPROP 1 LAST HDL_TAP TRUE
J 2
(-3075 3975);
DISPLAY 0.872340 (-3075 3975);
DISPLAY INVISIBLE (-3075 3975);
FORCEPROP 1 LAST PATH I75
J 2
(-2748 4100);
DISPLAY 0.872340 (-2748 4100);
PAINT GREEN (-2748 4100);
DISPLAY INVISIBLE (-2748 4100);
FORCEADD TAP..1
R 2
(-2750 4200);
FORCEPROP 3 LASTPIN (-2700 4200) SIG_NAME M_F_CPU0_SA_CA<2>
J 0
(-2690 4210);
DISPLAY 0.659574 (-2690 4210);
PAINT MONO (-2690 4210);
DISPLAY INVISIBLE (-2690 4210);
FORCEPROP 1 LASTPIN (-2700 4200) BN 2
J 2
(-2688 4208);
DISPLAY 0.680851 (-2688 4208);
PAINT GREEN (-2688 4208);
FORCEPROP 2 LAST CDS_LIB standard
J 0
(-2750 4200);
DISPLAY INVISIBLE (-2750 4200);
FORCEPROP 1 LAST BODY_TYPE PLUMBING
J 2
(-2750 4250);
DISPLAY 0.872340 (-2750 4250);
PAINT GREEN (-2750 4250);
DISPLAY INVISIBLE (-2750 4250);
FORCEPROP 1 LAST HDL_TAP TRUE
J 2
(-3075 4075);
DISPLAY 0.872340 (-3075 4075);
DISPLAY INVISIBLE (-3075 4075);
FORCEPROP 1 LAST PATH I76
J 2
(-2748 4200);
DISPLAY 0.872340 (-2748 4200);
PAINT GREEN (-2748 4200);
DISPLAY INVISIBLE (-2748 4200);
FORCEADD TAP..1
R 2
(-2750 4250);
FORCEPROP 3 LASTPIN (-2700 4250) SIG_NAME M_F_CPU0_SA_CA<3>
J 0
(-2690 4260);
DISPLAY 0.659574 (-2690 4260);
PAINT MONO (-2690 4260);
DISPLAY INVISIBLE (-2690 4260);
FORCEPROP 1 LASTPIN (-2700 4250) BN 3
J 2
(-2688 4258);
DISPLAY 0.680851 (-2688 4258);
PAINT GREEN (-2688 4258);
FORCEPROP 2 LAST CDS_LIB standard
J 0
(-2750 4250);
DISPLAY INVISIBLE (-2750 4250);
FORCEPROP 1 LAST BODY_TYPE PLUMBING
J 2
(-2750 4300);
DISPLAY 0.872340 (-2750 4300);
PAINT GREEN (-2750 4300);
DISPLAY INVISIBLE (-2750 4300);
FORCEPROP 1 LAST HDL_TAP TRUE
J 2
(-3075 4125);
DISPLAY 0.872340 (-3075 4125);
DISPLAY INVISIBLE (-3075 4125);
FORCEPROP 1 LAST PATH I77
J 2
(-2748 4250);
DISPLAY 0.872340 (-2748 4250);
PAINT GREEN (-2748 4250);
DISPLAY INVISIBLE (-2748 4250);
FORCEADD TAP..1
R 2
(-2750 4300);
FORCEPROP 3 LASTPIN (-2700 4300) SIG_NAME M_F_CPU0_SA_CA<4>
J 0
(-2690 4310);
DISPLAY 0.659574 (-2690 4310);
PAINT MONO (-2690 4310);
DISPLAY INVISIBLE (-2690 4310);
FORCEPROP 1 LASTPIN (-2700 4300) BN 4
J 2
(-2688 4308);
DISPLAY 0.680851 (-2688 4308);
PAINT GREEN (-2688 4308);
FORCEPROP 2 LAST CDS_LIB standard
J 0
(-2750 4300);
DISPLAY INVISIBLE (-2750 4300);
FORCEPROP 1 LAST BODY_TYPE PLUMBING
J 2
(-2750 4350);
DISPLAY 0.872340 (-2750 4350);
PAINT GREEN (-2750 4350);
DISPLAY INVISIBLE (-2750 4350);
FORCEPROP 1 LAST HDL_TAP TRUE
J 2
(-3075 4175);
DISPLAY 0.872340 (-3075 4175);
DISPLAY INVISIBLE (-3075 4175);
FORCEPROP 1 LAST PATH I78
J 2
(-2748 4300);
DISPLAY 0.872340 (-2748 4300);
PAINT GREEN (-2748 4300);
DISPLAY INVISIBLE (-2748 4300);
FORCEADD TAP..1
R 2
(-2750 4350);
FORCEPROP 3 LASTPIN (-2700 4350) SIG_NAME M_F_CPU0_SA_CA<5>
J 0
(-2690 4360);
DISPLAY 0.659574 (-2690 4360);
PAINT MONO (-2690 4360);
DISPLAY INVISIBLE (-2690 4360);
FORCEPROP 1 LASTPIN (-2700 4350) BN 5
J 2
(-2688 4358);
DISPLAY 0.680851 (-2688 4358);
PAINT GREEN (-2688 4358);
FORCEPROP 2 LAST CDS_LIB standard
J 0
(-2750 4350);
DISPLAY INVISIBLE (-2750 4350);
FORCEPROP 1 LAST BODY_TYPE PLUMBING
J 2
(-2750 4400);
DISPLAY 0.872340 (-2750 4400);
PAINT GREEN (-2750 4400);
DISPLAY INVISIBLE (-2750 4400);
FORCEPROP 1 LAST HDL_TAP TRUE
J 2
(-3075 4225);
DISPLAY 0.872340 (-3075 4225);
DISPLAY INVISIBLE (-3075 4225);
FORCEPROP 1 LAST PATH I79
J 2
(-2748 4350);
DISPLAY 0.872340 (-2748 4350);
PAINT GREEN (-2748 4350);
DISPLAY INVISIBLE (-2748 4350);
FORCEADD TAP..1
R 2
(-2750 4400);
FORCEPROP 3 LASTPIN (-2700 4400) SIG_NAME M_F_CPU0_SA_CA<6>
J 0
(-2690 4410);
DISPLAY 0.659574 (-2690 4410);
PAINT MONO (-2690 4410);
DISPLAY INVISIBLE (-2690 4410);
FORCEPROP 1 LASTPIN (-2700 4400) BN 6
J 2
(-2688 4408);
DISPLAY 0.680851 (-2688 4408);
PAINT GREEN (-2688 4408);
FORCEPROP 2 LAST CDS_LIB standard
J 0
(-2750 4400);
DISPLAY INVISIBLE (-2750 4400);
FORCEPROP 1 LAST BODY_TYPE PLUMBING
J 2
(-2750 4450);
DISPLAY 0.872340 (-2750 4450);
PAINT GREEN (-2750 4450);
DISPLAY INVISIBLE (-2750 4450);
FORCEPROP 1 LAST HDL_TAP TRUE
J 2
(-3075 4275);
DISPLAY 0.872340 (-3075 4275);
DISPLAY INVISIBLE (-3075 4275);
FORCEPROP 1 LAST PATH I80
J 2
(-2748 4400);
DISPLAY 0.872340 (-2748 4400);
PAINT GREEN (-2748 4400);
DISPLAY INVISIBLE (-2748 4400);
FORCEADD TAP..1
(-1100 2550);
FORCEPROP 3 LASTPIN (-1150 2550) SIG_NAME M_F_CPU0_SB_DQ<27>
J 0
(-1140 2560);
DISPLAY 0.659574 (-1140 2560);
PAINT MONO (-1140 2560);
DISPLAY INVISIBLE (-1140 2560);
FORCEPROP 1 LASTPIN (-1150 2550) BN 27
J 0
(-1162 2558);
DISPLAY 0.680851 (-1162 2558);
PAINT GREEN (-1162 2558);
FORCEPROP 2 LAST CDS_LIB standard
J 0
(-1100 2550);
DISPLAY INVISIBLE (-1100 2550);
FORCEPROP 1 LAST BODY_TYPE PLUMBING
J 0
(-1100 2600);
DISPLAY 0.872340 (-1100 2600);
PAINT GREEN (-1100 2600);
DISPLAY INVISIBLE (-1100 2600);
FORCEPROP 1 LAST HDL_TAP TRUE
J 0
(-775 2425);
DISPLAY 0.872340 (-775 2425);
DISPLAY INVISIBLE (-775 2425);
FORCEPROP 1 LAST PATH I81
J 0
(-1102 2550);
DISPLAY 0.872340 (-1102 2550);
PAINT GREEN (-1102 2550);
DISPLAY INVISIBLE (-1102 2550);
FORCEADD TAP..1
(-1100 2500);
FORCEPROP 3 LASTPIN (-1150 2500) SIG_NAME M_F_CPU0_SB_DQ<26>
J 0
(-1140 2510);
DISPLAY 0.659574 (-1140 2510);
PAINT MONO (-1140 2510);
DISPLAY INVISIBLE (-1140 2510);
FORCEPROP 1 LASTPIN (-1150 2500) BN 26
J 0
(-1162 2508);
DISPLAY 0.680851 (-1162 2508);
PAINT GREEN (-1162 2508);
FORCEPROP 2 LAST CDS_LIB standard
J 0
(-1100 2500);
DISPLAY INVISIBLE (-1100 2500);
FORCEPROP 1 LAST BODY_TYPE PLUMBING
J 0
(-1100 2550);
DISPLAY 0.872340 (-1100 2550);
PAINT GREEN (-1100 2550);
DISPLAY INVISIBLE (-1100 2550);
FORCEPROP 1 LAST HDL_TAP TRUE
J 0
(-775 2375);
DISPLAY 0.872340 (-775 2375);
DISPLAY INVISIBLE (-775 2375);
FORCEPROP 1 LAST PATH I82
J 0
(-1102 2500);
DISPLAY 0.872340 (-1102 2500);
PAINT GREEN (-1102 2500);
DISPLAY INVISIBLE (-1102 2500);
FORCEADD TAP..1
(-1100 2450);
FORCEPROP 3 LASTPIN (-1150 2450) SIG_NAME M_F_CPU0_SB_DQ<25>
J 0
(-1140 2460);
DISPLAY 0.659574 (-1140 2460);
PAINT MONO (-1140 2460);
DISPLAY INVISIBLE (-1140 2460);
FORCEPROP 1 LASTPIN (-1150 2450) BN 25
J 0
(-1162 2458);
DISPLAY 0.680851 (-1162 2458);
PAINT GREEN (-1162 2458);
FORCEPROP 2 LAST CDS_LIB standard
J 0
(-1100 2450);
DISPLAY INVISIBLE (-1100 2450);
FORCEPROP 1 LAST BODY_TYPE PLUMBING
J 0
(-1100 2500);
DISPLAY 0.872340 (-1100 2500);
PAINT GREEN (-1100 2500);
DISPLAY INVISIBLE (-1100 2500);
FORCEPROP 1 LAST HDL_TAP TRUE
J 0
(-775 2325);
DISPLAY 0.872340 (-775 2325);
DISPLAY INVISIBLE (-775 2325);
FORCEPROP 1 LAST PATH I83
J 0
(-1102 2450);
DISPLAY 0.872340 (-1102 2450);
PAINT GREEN (-1102 2450);
DISPLAY INVISIBLE (-1102 2450);
FORCEADD TAP..1
(-1100 2650);
FORCEPROP 3 LASTPIN (-1150 2650) SIG_NAME M_F_CPU0_SB_DQ<29>
J 0
(-1140 2660);
DISPLAY 0.659574 (-1140 2660);
PAINT MONO (-1140 2660);
DISPLAY INVISIBLE (-1140 2660);
FORCEPROP 1 LASTPIN (-1150 2650) BN 29
J 0
(-1162 2658);
DISPLAY 0.680851 (-1162 2658);
PAINT GREEN (-1162 2658);
FORCEPROP 2 LAST CDS_LIB standard
J 0
(-1100 2650);
DISPLAY INVISIBLE (-1100 2650);
FORCEPROP 1 LAST BODY_TYPE PLUMBING
J 0
(-1100 2700);
DISPLAY 0.872340 (-1100 2700);
PAINT GREEN (-1100 2700);
DISPLAY INVISIBLE (-1100 2700);
FORCEPROP 1 LAST HDL_TAP TRUE
J 0
(-775 2525);
DISPLAY 0.872340 (-775 2525);
DISPLAY INVISIBLE (-775 2525);
FORCEPROP 1 LAST PATH I84
J 0
(-1102 2650);
DISPLAY 0.872340 (-1102 2650);
PAINT GREEN (-1102 2650);
DISPLAY INVISIBLE (-1102 2650);
FORCEADD TAP..1
(-1100 2600);
FORCEPROP 3 LASTPIN (-1150 2600) SIG_NAME M_F_CPU0_SB_DQ<28>
J 0
(-1140 2610);
DISPLAY 0.659574 (-1140 2610);
PAINT MONO (-1140 2610);
DISPLAY INVISIBLE (-1140 2610);
FORCEPROP 1 LASTPIN (-1150 2600) BN 28
J 0
(-1162 2608);
DISPLAY 0.680851 (-1162 2608);
PAINT GREEN (-1162 2608);
FORCEPROP 2 LAST CDS_LIB standard
J 0
(-1100 2600);
DISPLAY INVISIBLE (-1100 2600);
FORCEPROP 1 LAST BODY_TYPE PLUMBING
J 0
(-1100 2650);
DISPLAY 0.872340 (-1100 2650);
PAINT GREEN (-1100 2650);
DISPLAY INVISIBLE (-1100 2650);
FORCEPROP 1 LAST HDL_TAP TRUE
J 0
(-775 2475);
DISPLAY 0.872340 (-775 2475);
DISPLAY INVISIBLE (-775 2475);
FORCEPROP 1 LAST PATH I85
J 0
(-1102 2600);
DISPLAY 0.872340 (-1102 2600);
PAINT GREEN (-1102 2600);
DISPLAY INVISIBLE (-1102 2600);
FORCEADD TAP..1
(-1100 2750);
FORCEPROP 3 LASTPIN (-1150 2750) SIG_NAME M_F_CPU0_SB_DQ<31>
J 0
(-1140 2760);
DISPLAY 0.659574 (-1140 2760);
PAINT MONO (-1140 2760);
DISPLAY INVISIBLE (-1140 2760);
FORCEPROP 1 LASTPIN (-1150 2750) BN 31
J 0
(-1162 2758);
DISPLAY 0.680851 (-1162 2758);
PAINT GREEN (-1162 2758);
FORCEPROP 2 LAST CDS_LIB standard
J 0
(-1100 2750);
DISPLAY INVISIBLE (-1100 2750);
FORCEPROP 1 LAST BODY_TYPE PLUMBING
J 0
(-1100 2800);
DISPLAY 0.872340 (-1100 2800);
PAINT GREEN (-1100 2800);
DISPLAY INVISIBLE (-1100 2800);
FORCEPROP 1 LAST HDL_TAP TRUE
J 0
(-775 2625);
DISPLAY 0.872340 (-775 2625);
DISPLAY INVISIBLE (-775 2625);
FORCEPROP 1 LAST PATH I86
J 0
(-1102 2750);
DISPLAY 0.872340 (-1102 2750);
PAINT GREEN (-1102 2750);
DISPLAY INVISIBLE (-1102 2750);
FORCEADD TAP..1
(-1100 2700);
FORCEPROP 3 LASTPIN (-1150 2700) SIG_NAME M_F_CPU0_SB_DQ<30>
J 0
(-1140 2710);
DISPLAY 0.659574 (-1140 2710);
PAINT MONO (-1140 2710);
DISPLAY INVISIBLE (-1140 2710);
FORCEPROP 1 LASTPIN (-1150 2700) BN 30
J 0
(-1162 2708);
DISPLAY 0.680851 (-1162 2708);
PAINT GREEN (-1162 2708);
FORCEPROP 2 LAST CDS_LIB standard
J 0
(-1100 2700);
DISPLAY INVISIBLE (-1100 2700);
FORCEPROP 1 LAST BODY_TYPE PLUMBING
J 0
(-1100 2750);
DISPLAY 0.872340 (-1100 2750);
PAINT GREEN (-1100 2750);
DISPLAY INVISIBLE (-1100 2750);
FORCEPROP 1 LAST HDL_TAP TRUE
J 0
(-775 2575);
DISPLAY 0.872340 (-775 2575);
DISPLAY INVISIBLE (-775 2575);
FORCEPROP 1 LAST PATH I87
J 0
(-1102 2700);
DISPLAY 0.872340 (-1102 2700);
PAINT GREEN (-1102 2700);
DISPLAY INVISIBLE (-1102 2700);
FORCEADD TAP..1
(-1100 2850);
FORCEPROP 3 LASTPIN (-1150 2850) SIG_NAME M_F_CPU0_SA_DQ<0>
J 0
(-1140 2860);
DISPLAY 0.659574 (-1140 2860);
PAINT MONO (-1140 2860);
DISPLAY INVISIBLE (-1140 2860);
FORCEPROP 1 LASTPIN (-1150 2850) BN 0
J 0
(-1162 2858);
DISPLAY 0.680851 (-1162 2858);
PAINT GREEN (-1162 2858);
FORCEPROP 2 LAST CDS_LIB standard
J 0
(-1100 2850);
PAINT MONO (-1100 2850);
DISPLAY INVISIBLE (-1100 2850);
FORCEPROP 1 LAST BODY_TYPE PLUMBING
J 0
(-1100 2900);
DISPLAY 0.872340 (-1100 2900);
PAINT GREEN (-1100 2900);
DISPLAY INVISIBLE (-1100 2900);
FORCEPROP 1 LAST HDL_TAP TRUE
J 0
(-775 2725);
DISPLAY 0.872340 (-775 2725);
DISPLAY INVISIBLE (-775 2725);
FORCEPROP 1 LAST PATH I88
J 0
(-1102 2850);
DISPLAY 0.872340 (-1102 2850);
PAINT GREEN (-1102 2850);
DISPLAY INVISIBLE (-1102 2850);
FORCEADD TAP..1
(-1100 2900);
FORCEPROP 3 LASTPIN (-1150 2900) SIG_NAME M_F_CPU0_SA_DQ<1>
J 0
(-1140 2910);
DISPLAY 0.659574 (-1140 2910);
PAINT MONO (-1140 2910);
DISPLAY INVISIBLE (-1140 2910);
FORCEPROP 1 LASTPIN (-1150 2900) BN 1
J 0
(-1162 2908);
DISPLAY 0.680851 (-1162 2908);
PAINT GREEN (-1162 2908);
FORCEPROP 2 LAST CDS_LIB standard
J 0
(-1100 2900);
PAINT MONO (-1100 2900);
DISPLAY INVISIBLE (-1100 2900);
FORCEPROP 1 LAST BODY_TYPE PLUMBING
J 0
(-1100 2950);
DISPLAY 0.872340 (-1100 2950);
PAINT GREEN (-1100 2950);
DISPLAY INVISIBLE (-1100 2950);
FORCEPROP 1 LAST HDL_TAP TRUE
J 0
(-775 2775);
DISPLAY 0.872340 (-775 2775);
DISPLAY INVISIBLE (-775 2775);
FORCEPROP 1 LAST PATH I89
J 0
(-1102 2900);
DISPLAY 0.872340 (-1102 2900);
PAINT GREEN (-1102 2900);
DISPLAY INVISIBLE (-1102 2900);
FORCEADD OFFPAGE..1
(-3600 1900);
FORCEPROP 2 LAST $XR0 92 
J 0
(-4061 1900);
DISPLAY 0.638298 (-4061 1900);
PAINT MONO (-4061 1900);
FORCEPROP 2 LAST CDS_LIB standard
J 0
(-3600 1900);
PAINT MONO (-3600 1900);
DISPLAY INVISIBLE (-3600 1900);
FORCEPROP 1 LAST OFFPAGE TRUE
J 0
(-3275 1775);
DISPLAY 0.872340 (-3275 1775);
DISPLAY INVISIBLE (-3275 1775);
FORCEPROP 1 LAST COMMENT_BODY TRUE
J 0
(-3475 1800);
DISPLAY 0.872340 (-3475 1800);
PAINT GREEN (-3475 1800);
DISPLAY INVISIBLE (-3475 1800);
FORCEPROP 2 LAST PATH I9
J 0
(-3550 1975);
DISPLAY 1.021277 (-3550 1975);
DISPLAY INVISIBLE (-3550 1975);
FORCEADD TAP..1
(-1100 3050);
FORCEPROP 3 LASTPIN (-1150 3050) SIG_NAME M_F_CPU0_SA_DQ<4>
J 0
(-1140 3060);
DISPLAY 0.659574 (-1140 3060);
PAINT MONO (-1140 3060);
DISPLAY INVISIBLE (-1140 3060);
FORCEPROP 1 LASTPIN (-1150 3050) BN 4
J 0
(-1162 3058);
DISPLAY 0.680851 (-1162 3058);
PAINT GREEN (-1162 3058);
FORCEPROP 2 LAST CDS_LIB standard
J 0
(-1100 3050);
PAINT MONO (-1100 3050);
DISPLAY INVISIBLE (-1100 3050);
FORCEPROP 1 LAST BODY_TYPE PLUMBING
J 0
(-1100 3100);
DISPLAY 0.872340 (-1100 3100);
PAINT GREEN (-1100 3100);
DISPLAY INVISIBLE (-1100 3100);
FORCEPROP 1 LAST HDL_TAP TRUE
J 0
(-775 2925);
DISPLAY 0.872340 (-775 2925);
DISPLAY INVISIBLE (-775 2925);
FORCEPROP 1 LAST PATH I90
J 0
(-1102 3050);
DISPLAY 0.872340 (-1102 3050);
PAINT GREEN (-1102 3050);
DISPLAY INVISIBLE (-1102 3050);
FORCEADD TAP..1
(-1100 3000);
FORCEPROP 3 LASTPIN (-1150 3000) SIG_NAME M_F_CPU0_SA_DQ<3>
J 0
(-1140 3010);
DISPLAY 0.659574 (-1140 3010);
PAINT MONO (-1140 3010);
DISPLAY INVISIBLE (-1140 3010);
FORCEPROP 1 LASTPIN (-1150 3000) BN 3
J 0
(-1162 3008);
DISPLAY 0.680851 (-1162 3008);
PAINT GREEN (-1162 3008);
FORCEPROP 2 LAST CDS_LIB standard
J 0
(-1100 3000);
PAINT MONO (-1100 3000);
DISPLAY INVISIBLE (-1100 3000);
FORCEPROP 1 LAST BODY_TYPE PLUMBING
J 0
(-1100 3050);
DISPLAY 0.872340 (-1100 3050);
PAINT GREEN (-1100 3050);
DISPLAY INVISIBLE (-1100 3050);
FORCEPROP 1 LAST HDL_TAP TRUE
J 0
(-775 2875);
DISPLAY 0.872340 (-775 2875);
DISPLAY INVISIBLE (-775 2875);
FORCEPROP 1 LAST PATH I91
J 0
(-1102 3000);
DISPLAY 0.872340 (-1102 3000);
PAINT GREEN (-1102 3000);
DISPLAY INVISIBLE (-1102 3000);
FORCEADD TAP..1
(-1100 2950);
FORCEPROP 3 LASTPIN (-1150 2950) SIG_NAME M_F_CPU0_SA_DQ<2>
J 0
(-1140 2960);
DISPLAY 0.659574 (-1140 2960);
PAINT MONO (-1140 2960);
DISPLAY INVISIBLE (-1140 2960);
FORCEPROP 1 LASTPIN (-1150 2950) BN 2
J 0
(-1162 2958);
DISPLAY 0.680851 (-1162 2958);
PAINT GREEN (-1162 2958);
FORCEPROP 2 LAST CDS_LIB standard
J 0
(-1100 2950);
PAINT MONO (-1100 2950);
DISPLAY INVISIBLE (-1100 2950);
FORCEPROP 1 LAST BODY_TYPE PLUMBING
J 0
(-1100 3000);
DISPLAY 0.872340 (-1100 3000);
PAINT GREEN (-1100 3000);
DISPLAY INVISIBLE (-1100 3000);
FORCEPROP 1 LAST HDL_TAP TRUE
J 0
(-775 2825);
DISPLAY 0.872340 (-775 2825);
DISPLAY INVISIBLE (-775 2825);
FORCEPROP 1 LAST PATH I92
J 0
(-1102 2950);
DISPLAY 0.872340 (-1102 2950);
PAINT GREEN (-1102 2950);
DISPLAY INVISIBLE (-1102 2950);
FORCEADD TAP..1
(-1100 3150);
FORCEPROP 3 LASTPIN (-1150 3150) SIG_NAME M_F_CPU0_SA_DQ<6>
J 0
(-1140 3160);
DISPLAY 0.659574 (-1140 3160);
PAINT MONO (-1140 3160);
DISPLAY INVISIBLE (-1140 3160);
FORCEPROP 1 LASTPIN (-1150 3150) BN 6
J 0
(-1162 3158);
DISPLAY 0.680851 (-1162 3158);
PAINT GREEN (-1162 3158);
FORCEPROP 2 LAST CDS_LIB standard
J 0
(-1100 3150);
PAINT MONO (-1100 3150);
DISPLAY INVISIBLE (-1100 3150);
FORCEPROP 1 LAST BODY_TYPE PLUMBING
J 0
(-1100 3200);
DISPLAY 0.872340 (-1100 3200);
PAINT GREEN (-1100 3200);
DISPLAY INVISIBLE (-1100 3200);
FORCEPROP 1 LAST HDL_TAP TRUE
J 0
(-775 3025);
DISPLAY 0.872340 (-775 3025);
DISPLAY INVISIBLE (-775 3025);
FORCEPROP 1 LAST PATH I93
J 0
(-1102 3150);
DISPLAY 0.872340 (-1102 3150);
PAINT GREEN (-1102 3150);
DISPLAY INVISIBLE (-1102 3150);
FORCEADD TAP..1
(-1100 3100);
FORCEPROP 3 LASTPIN (-1150 3100) SIG_NAME M_F_CPU0_SA_DQ<5>
J 0
(-1140 3110);
DISPLAY 0.659574 (-1140 3110);
PAINT MONO (-1140 3110);
DISPLAY INVISIBLE (-1140 3110);
FORCEPROP 1 LASTPIN (-1150 3100) BN 5
J 0
(-1162 3108);
DISPLAY 0.680851 (-1162 3108);
PAINT GREEN (-1162 3108);
FORCEPROP 2 LAST CDS_LIB standard
J 0
(-1100 3100);
PAINT MONO (-1100 3100);
DISPLAY INVISIBLE (-1100 3100);
FORCEPROP 1 LAST BODY_TYPE PLUMBING
J 0
(-1100 3150);
DISPLAY 0.872340 (-1100 3150);
PAINT GREEN (-1100 3150);
DISPLAY INVISIBLE (-1100 3150);
FORCEPROP 1 LAST HDL_TAP TRUE
J 0
(-775 2975);
DISPLAY 0.872340 (-775 2975);
DISPLAY INVISIBLE (-775 2975);
FORCEPROP 1 LAST PATH I94
J 0
(-1102 3100);
DISPLAY 0.872340 (-1102 3100);
PAINT GREEN (-1102 3100);
DISPLAY INVISIBLE (-1102 3100);
FORCEADD TAP..1
(-1100 3300);
FORCEPROP 3 LASTPIN (-1150 3300) SIG_NAME M_F_CPU0_SA_DQ<9>
J 0
(-1140 3310);
DISPLAY 0.659574 (-1140 3310);
PAINT MONO (-1140 3310);
DISPLAY INVISIBLE (-1140 3310);
FORCEPROP 1 LASTPIN (-1150 3300) BN 9
J 0
(-1162 3308);
DISPLAY 0.680851 (-1162 3308);
PAINT GREEN (-1162 3308);
FORCEPROP 2 LAST CDS_LIB standard
J 0
(-1100 3300);
PAINT MONO (-1100 3300);
DISPLAY INVISIBLE (-1100 3300);
FORCEPROP 1 LAST BODY_TYPE PLUMBING
J 0
(-1100 3350);
DISPLAY 0.872340 (-1100 3350);
PAINT GREEN (-1100 3350);
DISPLAY INVISIBLE (-1100 3350);
FORCEPROP 1 LAST HDL_TAP TRUE
J 0
(-775 3175);
DISPLAY 0.872340 (-775 3175);
DISPLAY INVISIBLE (-775 3175);
FORCEPROP 1 LAST PATH I95
J 0
(-1102 3300);
DISPLAY 0.872340 (-1102 3300);
PAINT GREEN (-1102 3300);
DISPLAY INVISIBLE (-1102 3300);
FORCEADD TAP..1
(-1100 3200);
FORCEPROP 3 LASTPIN (-1150 3200) SIG_NAME M_F_CPU0_SA_DQ<7>
J 0
(-1140 3210);
DISPLAY 0.659574 (-1140 3210);
PAINT MONO (-1140 3210);
DISPLAY INVISIBLE (-1140 3210);
FORCEPROP 1 LASTPIN (-1150 3200) BN 7
J 0
(-1162 3208);
DISPLAY 0.680851 (-1162 3208);
PAINT GREEN (-1162 3208);
FORCEPROP 2 LAST CDS_LIB standard
J 0
(-1100 3200);
PAINT MONO (-1100 3200);
DISPLAY INVISIBLE (-1100 3200);
FORCEPROP 1 LAST BODY_TYPE PLUMBING
J 0
(-1100 3250);
DISPLAY 0.872340 (-1100 3250);
PAINT GREEN (-1100 3250);
DISPLAY INVISIBLE (-1100 3250);
FORCEPROP 1 LAST HDL_TAP TRUE
J 0
(-775 3075);
DISPLAY 0.872340 (-775 3075);
DISPLAY INVISIBLE (-775 3075);
FORCEPROP 1 LAST PATH I96
J 0
(-1102 3200);
DISPLAY 0.872340 (-1102 3200);
PAINT GREEN (-1102 3200);
DISPLAY INVISIBLE (-1102 3200);
FORCEADD TAP..1
(-1100 3250);
FORCEPROP 3 LASTPIN (-1150 3250) SIG_NAME M_F_CPU0_SA_DQ<8>
J 0
(-1140 3260);
DISPLAY 0.659574 (-1140 3260);
PAINT MONO (-1140 3260);
DISPLAY INVISIBLE (-1140 3260);
FORCEPROP 1 LASTPIN (-1150 3250) BN 8
J 0
(-1162 3258);
DISPLAY 0.680851 (-1162 3258);
PAINT GREEN (-1162 3258);
FORCEPROP 2 LAST CDS_LIB standard
J 0
(-1100 3250);
PAINT MONO (-1100 3250);
DISPLAY INVISIBLE (-1100 3250);
FORCEPROP 1 LAST BODY_TYPE PLUMBING
J 0
(-1100 3300);
DISPLAY 0.872340 (-1100 3300);
PAINT GREEN (-1100 3300);
DISPLAY INVISIBLE (-1100 3300);
FORCEPROP 1 LAST HDL_TAP TRUE
J 0
(-775 3125);
DISPLAY 0.872340 (-775 3125);
DISPLAY INVISIBLE (-775 3125);
FORCEPROP 1 LAST PATH I97
J 0
(-1102 3250);
DISPLAY 0.872340 (-1102 3250);
PAINT GREEN (-1102 3250);
DISPLAY INVISIBLE (-1102 3250);
FORCEADD TAP..1
(-1100 3350);
FORCEPROP 3 LASTPIN (-1150 3350) SIG_NAME M_F_CPU0_SA_DQ<10>
J 0
(-1140 3360);
DISPLAY 0.659574 (-1140 3360);
PAINT MONO (-1140 3360);
DISPLAY INVISIBLE (-1140 3360);
FORCEPROP 1 LASTPIN (-1150 3350) BN 10
J 0
(-1162 3358);
DISPLAY 0.680851 (-1162 3358);
PAINT GREEN (-1162 3358);
FORCEPROP 2 LAST CDS_LIB standard
J 0
(-1100 3350);
PAINT MONO (-1100 3350);
DISPLAY INVISIBLE (-1100 3350);
FORCEPROP 1 LAST BODY_TYPE PLUMBING
J 0
(-1100 3400);
DISPLAY 0.872340 (-1100 3400);
PAINT GREEN (-1100 3400);
DISPLAY INVISIBLE (-1100 3400);
FORCEPROP 1 LAST HDL_TAP TRUE
J 0
(-775 3225);
DISPLAY 0.872340 (-775 3225);
DISPLAY INVISIBLE (-775 3225);
FORCEPROP 1 LAST PATH I98
J 0
(-1102 3350);
DISPLAY 0.872340 (-1102 3350);
PAINT GREEN (-1102 3350);
DISPLAY INVISIBLE (-1102 3350);
FORCEADD TAP..1
(-1100 3400);
FORCEPROP 3 LASTPIN (-1150 3400) SIG_NAME M_F_CPU0_SA_DQ<11>
J 0
(-1140 3410);
DISPLAY 0.659574 (-1140 3410);
PAINT MONO (-1140 3410);
DISPLAY INVISIBLE (-1140 3410);
FORCEPROP 1 LASTPIN (-1150 3400) BN 11
J 0
(-1162 3408);
DISPLAY 0.680851 (-1162 3408);
PAINT GREEN (-1162 3408);
FORCEPROP 2 LAST CDS_LIB standard
J 0
(-1100 3400);
PAINT MONO (-1100 3400);
DISPLAY INVISIBLE (-1100 3400);
FORCEPROP 1 LAST BODY_TYPE PLUMBING
J 0
(-1100 3450);
DISPLAY 0.872340 (-1100 3450);
PAINT GREEN (-1100 3450);
DISPLAY INVISIBLE (-1100 3450);
FORCEPROP 1 LAST HDL_TAP TRUE
J 0
(-775 3275);
DISPLAY 0.872340 (-775 3275);
DISPLAY INVISIBLE (-775 3275);
FORCEPROP 1 LAST PATH I99
J 0
(-1102 3400);
DISPLAY 0.872340 (-1102 3400);
PAINT GREEN (-1102 3400);
DISPLAY INVISIBLE (-1102 3400);
FORCEADD CAD_NOTE..1
(750 -50);
FORCEPROP 0 LAST S1 PLACE THE BYPASS CAPS CLOSE TO DIMM
J 0
(625 -175);
DISPLAY 1.021277 (625 -175);
PAINT WHITE (625 -175);
FORCEPROP 2 LAST CDS_LIB logical_power
J 0
(750 -50);
PAINT MONO (750 -50);
DISPLAY INVISIBLE (750 -50);
FORCEPROP 1 LAST COMMENT_BODY TRUE
J 0
(775 50);
DISPLAY 0.978723 (775 50);
DISPLAY INVISIBLE (775 50);
FORCEADD QUANTA_TITLE_BLOCK_C..1
(5225 -1350);
FORCEPROP 0 LAST CDS_CON_LAST_MODIFIED Fri Aug 25 14:01:11 2023
J 0
(3340 -1335);
PAINT MONO (3340 -1335);
DISPLAY INVISIBLE (3340 -1335);
FORCEPROP 2 LAST CUSTOM_TXT_CDS <XR_PAGE_TITLE>
J 0
(-2665 3900);
DISPLAY 0.638298 (-2665 3900);
PAINT PINK (-2665 3900);
DISPLAY INVISIBLE (-2665 3900);
FORCEPROP 2 LAST CUSTOM_TXT_CDS <Q_PROJ>
J 0
(2843 -1248);
DISPLAY 1.212766 (2843 -1248);
FORCEPROP 2 LAST CUSTOM_TXT_CDS <NAME_2>
J 0
(2050 -1300);
FORCEPROP 2 LAST CUSTOM_TXT_CDS <NAME_1>
J 0
(2050 -1175);
FORCEPROP 2 LAST CUSTOM_TXT_CDS <CON_LAST_MODIFIED>
J 0
(3340 -1335);
DISPLAY 0.978723 (3340 -1335);
FORCEPROP 2 LAST CUSTOM_TXT_CDS <Q_NUMBER>
J 0
(3822 -1247);
DISPLAY 1.212766 (3822 -1247);
FORCEPROP 2 LAST CUSTOM_TXT_CDS <CON_PAGE_NUM> OF <CON_TOTAL_PAGES>
J 0
(4779 -1332);
DISPLAY 0.978723 (4779 -1332);
FORCEPROP 2 LAST CUSTOM_TXT_CDS <Q_REV>
J 0
(5041 -1247);
DISPLAY 1.212766 (5041 -1247);
FORCEPROP 1 LAST Q_TITLE DDR5 - CPU0 CHF DIMM1(YELLOW)
J 0
(-4141 -1324);
DISPLAY 2.446809 (-4141 -1324);
PAINT GREEN (-4141 -1324);
FORCEPROP 1 LAST Q_DEPT 
J 1
(1462 -1301);
DISPLAY 1.957447 (1462 -1301);
PAINT GREEN (1462 -1301);
FORCEPROP 1 LAST COMMENT_BODY TRUE
J 0
(5237 -1363);
DISPLAY 0.978723 (5237 -1363);
PAINT GREEN (5237 -1363);
DISPLAY INVISIBLE (5237 -1363);
FORCEPROP 2 LAST CDS_XR_PAGE_TITLE CR-92 : @S9S_MB_2U_LIB.S9S_MB_2U(SCH_1):PAGE92
J 0
(-2665 3900);
DISPLAY 0.638298 (-2665 3900);
PAINT PINK (-2665 3900);
DISPLAY INVISIBLE (-2665 3900);
FORCEPROP 2 LAST PAGE_BORDER TRUE
J 0
(-2665 3900);
DISPLAY 0.638298 (-2665 3900);
PAINT PINK (-2665 3900);
DISPLAY INVISIBLE (-2665 3900);
FORCEPROP 1 LAST CDS_LMAN_SYM_OUTLINE -9475,6775,100,-125
J 0
(5225 -1350);
DISPLAY 0.468085 (5225 -1350);
PAINT GREEN (5225 -1350);
DISPLAY INVISIBLE (5225 -1350);
FORCEPROP 2 LAST CDS_LIB pure_quanta
J 0
(5225 -1350);
PAINT MONO (5225 -1350);
DISPLAY INVISIBLE (5225 -1350);
WIRE 17 -1 (-3625 3025)(-2800 3025);
FORCEPROP 2 LAST SIG_NAME M_F_CPU0_SA_CB<7:0>
J 0
(-3535 3035);
DISPLAY 0.680851 (-3535 3035);
PAINT WHITE (-3535 3035);
WIRE 17 -1 (-2800 2725)(-2800 2775);
WIRE 17 -1 (-2800 2675)(-2800 2725);
WIRE 17 -1 (-2800 2775)(-2800 2825);
WIRE 17 -1 (-2800 2825)(-2800 2875);
WIRE 17 -1 (-2800 2875)(-2800 2925);
WIRE 17 -1 (-2800 2925)(-2800 2975);
WIRE 17 -1 (-2800 2975)(-2800 3025);
WIRE 17 -1 (-3625 2575)(-2800 2575);
FORCEPROP 2 LAST SIG_NAME M_F_CPU0_SB_CB<7:0>
J 0
(-3535 2585);
DISPLAY 0.680851 (-3535 2585);
PAINT WHITE (-3535 2585);
WIRE 17 -1 (-2800 4125)(-2800 4175);
WIRE 17 -1 (-2800 4175)(-2800 4225);
WIRE 17 -1 (-2800 4225)(-2800 4275);
WIRE 17 -1 (-2800 4275)(-2800 4325);
WIRE 17 -1 (-2800 4325)(-2800 4375);
WIRE 17 -1 (-2800 4375)(-2800 4425);
WIRE 17 -1 (-3625 4425)(-2800 4425);
FORCEPROP 2 LAST SIG_NAME M_F_CPU0_SA_CA<6:0>
J 0
(-3535 4435);
DISPLAY 0.680851 (-3535 4435);
PAINT WHITE (-3535 4435);
WIRE 17 -1 (-2800 3725)(-2800 3775);
WIRE 17 -1 (-2800 3775)(-2800 3825);
WIRE 17 -1 (-2800 3825)(-2800 3875);
WIRE 17 -1 (-2800 3875)(-2800 3925);
WIRE 17 -1 (-2800 3925)(-2800 3975);
WIRE 17 -1 (-2800 3975)(-2800 4025);
WIRE 17 -1 (-3625 4025)(-2800 4025);
FORCEPROP 2 LAST SIG_NAME M_F_CPU0_SB_CA<6:0>
J 0
(-3535 4035);
DISPLAY 0.680851 (-3535 4035);
PAINT WHITE (-3535 4035);
WIRE 17 -1 (-2800 2525)(-2800 2575);
WIRE 17 -1 (-2800 2475)(-2800 2525);
WIRE 17 -1 (-2800 2425)(-2800 2475);
WIRE 17 -1 (-2800 2375)(-2800 2425);
WIRE 17 -1 (-2800 2325)(-2800 2375);
WIRE 17 -1 (-2800 2275)(-2800 2325);
WIRE 17 -1 (-2800 2225)(-2800 2275);
WIRE 17 -1 (-1050 4275)(-1050 4325);
WIRE 17 -1 (-1050 4225)(-1050 4275);
WIRE 17 -1 (-1050 4325)(-1050 4375);
WIRE 17 -1 (-1050 4375)(-1050 4425);
WIRE 17 -1 (-1050 4175)(-1050 4225);
WIRE 17 -1 (-1050 4125)(-1050 4175);
WIRE 17 -1 (-1050 4425)(-325 4425);
FORCEPROP 2 LAST SIG_NAME M_F_CPU0_SA_DQ<31:0>
J 0
(-985 4435);
DISPLAY 0.680851 (-985 4435);
PAINT WHITE (-985 4435);
WIRE 17 -1 (-1050 4075)(-1050 4125);
WIRE 17 -1 (-1050 4025)(-1050 4075);
WIRE 17 -1 (-1050 3975)(-1050 4025);
WIRE 17 -1 (-1050 3925)(-1050 3975);
WIRE 17 -1 (-1050 3875)(-1050 3925);
WIRE 17 -1 (-1050 3825)(-1050 3875);
WIRE 17 -1 (-1050 3775)(-1050 3825);
WIRE 17 -1 (-1050 3725)(-1050 3775);
WIRE 17 -1 (-1050 3675)(-1050 3725);
WIRE 17 -1 (-1050 3625)(-1050 3675);
WIRE 17 -1 (-1050 3575)(-1050 3625);
WIRE 17 -1 (-1050 3525)(-1050 3575);
WIRE 17 -1 (-1050 3475)(-1050 3525);
WIRE 17 -1 (-1050 3425)(-1050 3475);
WIRE 17 -1 (-1050 3375)(-1050 3425);
WIRE 17 -1 (-1050 3325)(-1050 3375);
WIRE 17 -1 (-1050 3275)(-1050 3325);
WIRE 17 -1 (-1050 3225)(-1050 3275);
WIRE 17 -1 (-1050 3175)(-1050 3225);
WIRE 17 -1 (-1050 3125)(-1050 3175);
WIRE 17 -1 (-1050 3075)(-1050 3125);
WIRE 17 -1 (-1050 3025)(-1050 3075);
WIRE 17 -1 (-1050 2975)(-1050 3025);
WIRE 17 -1 (-1050 2925)(-1050 2975);
WIRE 17 -1 (-1050 2875)(-1050 2925);
WIRE 17 -1 (-1050 2775)(-325 2775);
FORCEPROP 2 LAST SIG_NAME M_F_CPU0_SB_DQ<31:0>
J 0
(-985 2785);
DISPLAY 0.680851 (-985 2785);
PAINT WHITE (-985 2785);
WIRE 17 -1 (-1050 2725)(-1050 2775);
WIRE 17 -1 (-1050 2675)(-1050 2725);
WIRE 17 -1 (-1050 2625)(-1050 2675);
WIRE 17 -1 (-1050 2575)(-1050 2625);
WIRE 17 -1 (-1050 2525)(-1050 2575);
WIRE 17 -1 (-1050 2475)(-1050 2525);
WIRE 17 -1 (-1050 2425)(-1050 2475);
WIRE 17 -1 (-1050 2375)(-1050 2425);
WIRE 17 -1 (-1050 2325)(-1050 2375);
WIRE 17 -1 (-1050 2275)(-1050 2325);
WIRE 17 -1 (-1050 2225)(-1050 2275);
WIRE 17 -1 (-1050 2175)(-1050 2225);
WIRE 17 -1 (-1050 2125)(-1050 2175);
WIRE 17 -1 (-1050 2075)(-1050 2125);
WIRE 17 -1 (-1050 2025)(-1050 2075);
WIRE 17 -1 (-1050 1975)(-1050 2025);
WIRE 17 -1 (-1050 1925)(-1050 1975);
WIRE 17 -1 (-1050 1875)(-1050 1925);
WIRE 17 -1 (-1050 1825)(-1050 1875);
WIRE 17 -1 (-1050 1775)(-1050 1825);
WIRE 17 -1 (-1050 1725)(-1050 1775);
WIRE 17 -1 (-1050 1675)(-1050 1725);
WIRE 17 -1 (-1050 1625)(-1050 1675);
WIRE 17 -1 (-1050 1575)(-1050 1625);
WIRE 17 -1 (-1050 1525)(-1050 1575);
WIRE 17 -1 (-1050 1475)(-1050 1525);
WIRE 17 -1 (-1050 1425)(-1050 1475);
WIRE 17 -1 (-1050 1375)(-1050 1425);
WIRE 17 -1 (-1050 1325)(-1050 1375);
WIRE 17 -1 (-1050 1275)(-1050 1325);
WIRE 17 -1 (-1050 1225)(-1050 1275);
WIRE 17 -1 (1700 2475)(1700 2575);
WIRE 17 -1 (1700 2575)(1700 2675);
WIRE 17 -1 (1700 2675)(1700 2775);
WIRE 17 -1 (1700 2875)(1700 2775);
WIRE 17 -1 (1700 2875)(1700 2975);
WIRE 17 -1 (1700 2975)(1700 3075);
WIRE 17 -1 (1700 3075)(1700 3175);
WIRE 17 -1 (1700 3175)(1700 3275);
WIRE 17 -1 (1700 3275)(1700 3375);
WIRE 17 -1 (1700 3375)(2725 3375);
FORCEPROP 2 LAST SIG_NAME M_F_CPU0_SB_DQS_DP<9:0>
J 0
(1940 3385);
DISPLAY 0.680851 (1940 3385);
PAINT WHITE (1940 3385);
WIRE 17 -1 (1700 3525)(1700 3625);
WIRE 17 -1 (1700 3625)(1700 3725);
WIRE 17 -1 (1700 3725)(1700 3825);
WIRE 17 -1 (1700 3925)(1700 3825);
WIRE 17 -1 (1700 3925)(1700 4025);
WIRE 17 -1 (1700 4025)(1700 4125);
WIRE 17 -1 (1700 4125)(1700 4225);
WIRE 17 -1 (1700 4225)(1700 4325);
WIRE 17 -1 (1700 4325)(1700 4425);
WIRE 17 -1 (1700 4425)(2725 4425);
FORCEPROP 2 LAST SIG_NAME M_F_CPU0_SA_DQS_DP<9:0>
J 0
(1940 4435);
DISPLAY 0.680851 (1940 4435);
PAINT WHITE (1940 4435);
WIRE 17 -1 (1875 2425)(1875 2525);
WIRE 17 -1 (1875 2525)(1875 2625);
WIRE 17 -1 (1875 2625)(1875 2725);
WIRE 17 -1 (1875 2825)(1875 2725);
WIRE 17 -1 (1875 2825)(1875 2925);
WIRE 17 -1 (1875 2925)(1875 3025);
WIRE 17 -1 (1875 3025)(1875 3125);
WIRE 17 -1 (1875 3125)(1875 3225);
WIRE 17 -1 (1875 3225)(1875 3325);
WIRE 17 -1 (1875 3325)(2725 3325);
FORCEPROP 2 LAST SIG_NAME M_F_CPU0_SB_DQS_DN<9:0>
J 0
(1940 3335);
DISPLAY 0.680851 (1940 3335);
PAINT WHITE (1940 3335);
WIRE 17 -1 (1875 3475)(1875 3575);
WIRE 17 -1 (1875 3575)(1875 3675);
WIRE 17 -1 (1875 3675)(1875 3775);
WIRE 17 -1 (1875 3875)(1875 3775);
WIRE 17 -1 (1875 3875)(1875 3975);
WIRE 17 -1 (1875 3975)(1875 4075);
WIRE 17 -1 (1875 4075)(1875 4175);
WIRE 17 -1 (1875 4175)(1875 4275);
WIRE 17 -1 (1875 4275)(1875 4375);
WIRE 17 -1 (1875 4375)(2725 4375);
FORCEPROP 2 LAST SIG_NAME M_F_CPU0_SA_DQS_DN<9:0>
J 0
(1940 4385);
DISPLAY 0.680851 (1940 4385);
PAINT WHITE (1940 4385);
WIRE 16 -1 (-3575 2225)(-3575 1950);
WIRE 16 -1 (1625 800)(1625 750);
WIRE 16 -1 (625 625)(625 800);
WIRE 16 -1 (3325 4900)(3325 4400);
WIRE 16 -1 (5025 1050)(5025 750);
WIRE 16 -1 (5025 1100)(5025 1050);
WIRE 16 -1 (4775 1050)(5025 1050);
WIRE 16 -1 (3325 750)(3325 1150);
WIRE 16 -1 (2250 200)(2250 275);
WIRE 16 -1 (625 425)(625 200);
WIRE 16 -1 (-2525 75)(-2525 150);
WIRE 16 -1 (-2525 1900)(-3550 1900);
FORCEPROP 2 LAST SIG_NAME PD_CHF_CPU0_DIMM1_SAA
J 0
(-3560 1910);
DISPLAY 0.680851 (-3560 1910);
PAINT WHITE (-3560 1910);
WIRE 16 -1 (-2525 1850)(-3550 1850);
FORCEPROP 2 LAST SIG_NAME I3C_SPD_DDREFGH_CPU0_LVC1_SDA
J 0
(-3560 1860);
DISPLAY 0.680851 (-3560 1860);
PAINT WHITE (-3560 1860);
WIRE 16 -1 (-4025 1700)(-3825 1700);
WIRE 16 -1 (-4025 1800)(-4025 1700);
WIRE 16 -1 (-2525 1800)(-4025 1800);
FORCEPROP 2 LAST SIG_NAME I3C_SPD_DDREFGH_CPU0_LVC1_SCL_R3
J 0
(-3585 1810);
DISPLAY 0.680851 (-3585 1810);
PAINT WHITE (-3585 1810);
WIRE 16 -1 (-2525 2050)(-3625 2050);
FORCEPROP 2 LAST SIG_NAME M_F_CPU0_ALERT_N
J 0
(-3537 2059);
DISPLAY 0.680851 (-3537 2059);
PAINT WHITE (-3537 2059);
WIRE 16 -1 (-3575 1950)(-2525 1950);
WIRE 16 -1 (-2900 2100)(-2525 2100);
WIRE 16 -1 (-2900 2150)(-3625 2150);
FORCEPROP 2 LAST SIG_NAME RST_M_EF_CPU0_FPGA_N
J 0
(-3537 2159);
DISPLAY 0.680851 (-3537 2159);
PAINT WHITE (-3537 2159);
WIRE 16 -1 (-2900 2150)(-2900 2100);
WIRE 16 -1 (-2400 1625)(-2450 1625);
WIRE 16 -1 (-3625 1700)(-2400 1700);
FORCEPROP 2 LAST SIG_NAME I3C_SPD_DDREFGH_CPU0_LVC1_SCL
J 0
(-3485 1710);
DISPLAY 0.680851 (-3485 1710);
PAINT WHITE (-3485 1710);
WIRE 16 -1 (-2400 1700)(-2400 1625);
WIRE 16 -1 (-2525 1550)(-3625 1550);
FORCEPROP 2 LAST SIG_NAME PWRGD_CHF_CPU0_DIMM1
J 0
(-3537 1559);
DISPLAY 0.680851 (-3537 1559);
PAINT WHITE (-3537 1559);
WIRE 16 -1 (-2525 1450)(-3625 1450);
FORCEPROP 2 LAST SIG_NAME TP_CHF_CPU0_DIMM1_FRU_6
J 0
(-3537 1459);
DISPLAY 0.680851 (-3537 1459);
PAINT WHITE (-3537 1459);
WIRE 16 -1 (1500 2600)(1775 2600);
WIRE 16 -1 (1500 4350)(1775 4350);
WIRE 16 -1 (1500 4250)(1775 4250);
WIRE 16 -1 (1500 4150)(1775 4150);
WIRE 16 -1 (1500 4050)(1775 4050);
WIRE 16 -1 (1500 3850)(1775 3850);
WIRE 16 -1 (1500 3950)(1775 3950);
WIRE 16 -1 (1500 3750)(1775 3750);
WIRE 16 -1 (1500 3650)(1775 3650);
WIRE 16 -1 (1500 3550)(1775 3550);
WIRE 16 -1 (1500 3450)(1775 3450);
WIRE 16 -1 (1500 3300)(1775 3300);
WIRE 16 -1 (1500 3200)(1775 3200);
WIRE 16 -1 (1500 3100)(1775 3100);
WIRE 16 -1 (1500 3000)(1775 3000);
WIRE 16 -1 (1500 2900)(1775 2900);
WIRE 16 -1 (1500 2700)(1775 2700);
WIRE 16 -1 (1500 2800)(1775 2800);
WIRE 16 -1 (1500 2500)(1775 2500);
WIRE 16 -1 (1500 2400)(1775 2400);
WIRE 16 -1 (1500 4400)(1600 4400);
WIRE 16 -1 (1500 4300)(1600 4300);
WIRE 16 -1 (1500 4200)(1600 4200);
WIRE 16 -1 (1500 4100)(1600 4100);
WIRE 16 -1 (1500 4000)(1600 4000);
WIRE 16 -1 (1500 3900)(1600 3900);
WIRE 16 -1 (1500 3800)(1600 3800);
WIRE 16 -1 (1500 3700)(1600 3700);
WIRE 16 -1 (1500 3600)(1600 3600);
WIRE 16 -1 (1500 3500)(1600 3500);
WIRE 16 -1 (1500 3350)(1600 3350);
WIRE 16 -1 (1500 3250)(1600 3250);
WIRE 16 -1 (1500 3150)(1600 3150);
WIRE 16 -1 (1500 3050)(1600 3050);
WIRE 16 -1 (1500 2950)(1600 2950);
WIRE 16 -1 (1500 2850)(1600 2850);
WIRE 16 -1 (1500 2750)(1600 2750);
WIRE 16 -1 (1500 2650)(1600 2650);
WIRE 16 -1 (1500 2550)(1600 2550);
WIRE 16 -1 (1500 2450)(1600 2450);
WIRE 16 -1 (-2525 1300)(-3625 1300);
FORCEPROP 2 LAST SIG_NAME TP_CHF_CPU0_DIMM1_FRU_3
J 0
(-3537 1309);
DISPLAY 0.680851 (-3537 1309);
PAINT WHITE (-3537 1309);
WIRE 16 -1 (3325 1150)(3575 1150);
WIRE 16 -1 (3325 1150)(3325 1200);
WIRE 16 -1 (3325 1200)(3575 1200);
WIRE 16 -1 (3325 1200)(3325 1250);
WIRE 16 -1 (3325 1250)(3575 1250);
WIRE 16 -1 (3325 1250)(3325 1300);
WIRE 16 -1 (3325 1300)(3575 1300);
WIRE 16 -1 (3325 1300)(3325 1350);
WIRE 16 -1 (3325 1350)(3575 1350);
WIRE 16 -1 (3325 1350)(3325 1400);
WIRE 16 -1 (3325 1400)(3575 1400);
WIRE 16 -1 (3325 1400)(3325 1450);
WIRE 16 -1 (3325 1450)(3575 1450);
WIRE 16 -1 (3325 1450)(3325 1500);
WIRE 16 -1 (3325 1500)(3575 1500);
WIRE 16 -1 (3325 1500)(3325 1550);
WIRE 16 -1 (3325 1550)(3575 1550);
WIRE 16 -1 (3325 1550)(3325 1600);
WIRE 16 -1 (3325 1600)(3575 1600);
WIRE 16 -1 (3325 1600)(3325 1650);
WIRE 16 -1 (3575 1650)(3325 1650);
WIRE 16 -1 (3325 1650)(3325 1700);
WIRE 16 -1 (3325 1700)(3575 1700);
WIRE 16 -1 (3325 1700)(3325 1750);
WIRE 16 -1 (3325 1750)(3575 1750);
WIRE 16 -1 (3325 1750)(3325 1800);
WIRE 16 -1 (3325 1800)(3575 1800);
WIRE 16 -1 (3325 1800)(3325 1850);
WIRE 16 -1 (3325 1850)(3575 1850);
WIRE 16 -1 (3325 1850)(3325 1900);
WIRE 16 -1 (3325 1900)(3575 1900);
WIRE 16 -1 (3325 1900)(3325 1950);
WIRE 16 -1 (3325 1950)(3575 1950);
WIRE 16 -1 (3325 1950)(3325 2000);
WIRE 16 -1 (3325 2000)(3575 2000);
WIRE 16 -1 (3325 2000)(3325 2050);
WIRE 16 -1 (3325 2050)(3575 2050);
WIRE 16 -1 (3325 2050)(3325 2100);
WIRE 16 -1 (3325 2100)(3575 2100);
WIRE 16 -1 (3325 2100)(3325 2150);
WIRE 16 -1 (3575 2150)(3325 2150);
WIRE 16 -1 (3325 2150)(3325 2200);
WIRE 16 -1 (3325 2200)(3575 2200);
WIRE 16 -1 (3325 2200)(3325 2250);
WIRE 16 -1 (3325 2250)(3575 2250);
WIRE 16 -1 (3325 2250)(3325 2300);
WIRE 16 -1 (3325 2300)(3575 2300);
WIRE 16 -1 (3325 2300)(3325 2350);
WIRE 16 -1 (3325 2350)(3575 2350);
WIRE 16 -1 (3325 2350)(3325 2400);
WIRE 16 -1 (3325 2400)(3575 2400);
WIRE 16 -1 (3325 2400)(3325 2450);
WIRE 16 -1 (3325 2450)(3575 2450);
WIRE 16 -1 (3325 2450)(3325 2500);
WIRE 16 -1 (3325 2500)(3575 2500);
WIRE 16 -1 (3325 2500)(3325 2550);
WIRE 16 -1 (3325 2550)(3575 2550);
WIRE 16 -1 (3325 2550)(3325 2600);
WIRE 16 -1 (3325 2600)(3575 2600);
WIRE 16 -1 (3325 2600)(3325 2650);
WIRE 16 -1 (3575 2650)(3325 2650);
WIRE 16 -1 (3325 2650)(3325 2700);
WIRE 16 -1 (3325 2700)(3575 2700);
WIRE 16 -1 (3325 2700)(3325 2750);
WIRE 16 -1 (3325 2750)(3575 2750);
WIRE 16 -1 (3325 2750)(3325 2800);
WIRE 16 -1 (3325 2800)(3575 2800);
WIRE 16 -1 (3325 2800)(3325 2850);
WIRE 16 -1 (3325 2850)(3575 2850);
WIRE 16 -1 (3325 2850)(3325 2900);
WIRE 16 -1 (3325 2900)(3575 2900);
WIRE 16 -1 (3325 2900)(3325 2950);
WIRE 16 -1 (3325 2950)(3575 2950);
WIRE 16 -1 (3325 2950)(3325 3000);
WIRE 16 -1 (3325 3000)(3575 3000);
WIRE 16 -1 (3325 3000)(3325 3050);
WIRE 16 -1 (3325 3050)(3575 3050);
WIRE 16 -1 (3325 3050)(3325 3100);
WIRE 16 -1 (3325 3100)(3575 3100);
WIRE 16 -1 (3325 3100)(3325 3150);
WIRE 16 -1 (3575 3150)(3325 3150);
WIRE 16 -1 (3325 3150)(3325 3200);
WIRE 16 -1 (3325 3200)(3575 3200);
WIRE 16 -1 (3325 3200)(3325 3250);
WIRE 16 -1 (3325 3250)(3575 3250);
WIRE 16 -1 (3325 3250)(3325 3300);
WIRE 16 -1 (3325 3300)(3575 3300);
WIRE 16 -1 (3325 3300)(3325 3350);
WIRE 16 -1 (3325 3350)(3575 3350);
WIRE 16 -1 (3325 3350)(3325 3400);
WIRE 16 -1 (3325 3400)(3575 3400);
WIRE 16 -1 (3325 3400)(3325 3450);
WIRE 16 -1 (3325 3450)(3575 3450);
WIRE 16 -1 (3325 3450)(3325 3500);
WIRE 16 -1 (3325 3500)(3575 3500);
WIRE 16 -1 (3325 3500)(3325 3550);
WIRE 16 -1 (3325 3550)(3575 3550);
WIRE 16 -1 (3325 3550)(3325 3600);
WIRE 16 -1 (3325 3600)(3575 3600);
WIRE 16 -1 (3325 3600)(3325 3650);
WIRE 16 -1 (3575 3650)(3325 3650);
WIRE 16 -1 (3325 3650)(3325 3700);
WIRE 16 -1 (3325 3700)(3575 3700);
WIRE 16 -1 (3325 3700)(3325 3750);
WIRE 16 -1 (3325 3750)(3575 3750);
WIRE 16 -1 (3325 3750)(3325 3800);
WIRE 16 -1 (3325 3800)(3575 3800);
WIRE 16 -1 (3325 3800)(3325 3850);
WIRE 16 -1 (3325 3850)(3575 3850);
WIRE 16 -1 (3325 3850)(3325 3900);
WIRE 16 -1 (3325 3900)(3575 3900);
WIRE 16 -1 (3325 3900)(3325 3950);
WIRE 16 -1 (3325 3950)(3575 3950);
WIRE 16 -1 (3325 3950)(3325 4000);
WIRE 16 -1 (3325 4000)(3575 4000);
WIRE 16 -1 (3325 4000)(3325 4050);
WIRE 16 -1 (3325 4050)(3575 4050);
WIRE 16 -1 (3325 4050)(3325 4100);
WIRE 16 -1 (3325 4100)(3575 4100);
WIRE 16 -1 (3325 4100)(3325 4150);
WIRE 16 -1 (3575 4150)(3325 4150);
WIRE 16 -1 (3325 4150)(3325 4200);
WIRE 16 -1 (3325 4200)(3575 4200);
WIRE 16 -1 (3325 4200)(3325 4250);
WIRE 16 -1 (3575 4250)(3325 4250);
WIRE 16 -1 (3575 4300)(3325 4300);
WIRE 16 -1 (3325 4350)(3325 4300);
WIRE 16 -1 (3325 4350)(3575 4350);
WIRE 16 -1 (3325 4400)(3325 4350);
WIRE 16 -1 (3575 4400)(3325 4400);
WIRE 16 -1 (-1325 4350)(-1150 4350);
WIRE 16 -1 (-1325 4400)(-1150 4400);
WIRE 16 -1 (-1325 3300)(-1150 3300);
WIRE 16 -1 (-1325 3450)(-1150 3450);
WIRE 16 -1 (-2700 2850)(-2525 2850);
WIRE 16 -1 (-1325 2150)(-1150 2150);
WIRE 16 -1 (-1325 1500)(-1150 1500);
WIRE 16 -1 (-2525 1150)(-3625 1150);
FORCEPROP 2 LAST SIG_NAME TP_CHF_CPU0_DIMM1_FRU_0
J 0
(-3537 1159);
DISPLAY 0.680851 (-3537 1159);
PAINT WHITE (-3537 1159);
WIRE 16 -1 (-2525 950)(-3625 950);
FORCEPROP 2 LAST SIG_NAME M_F_CPU0_SB_RSP<0>
J 0
(-3537 959);
DISPLAY 0.680851 (-3537 959);
PAINT WHITE (-3537 959);
WIRE 16 -1 (4775 4400)(5025 4400);
WIRE 16 -1 (4775 4350)(5025 4350);
WIRE 16 -1 (5025 4400)(5025 4350);
WIRE 16 -1 (4775 4300)(5025 4300);
WIRE 16 -1 (5025 4350)(5025 4300);
WIRE 16 -1 (4775 4250)(5025 4250);
WIRE 16 -1 (5025 4300)(5025 4250);
WIRE 16 -1 (4775 4200)(5025 4200);
WIRE 16 -1 (5025 4250)(5025 4200);
WIRE 16 -1 (4775 4150)(5025 4150);
WIRE 16 -1 (5025 4200)(5025 4150);
WIRE 16 -1 (4775 4100)(5025 4100);
WIRE 16 -1 (5025 4150)(5025 4100);
WIRE 16 -1 (4775 4050)(5025 4050);
WIRE 16 -1 (5025 4100)(5025 4050);
WIRE 16 -1 (4775 4000)(5025 4000);
WIRE 16 -1 (5025 4050)(5025 4000);
WIRE 16 -1 (4775 3950)(5025 3950);
WIRE 16 -1 (5025 4000)(5025 3950);
WIRE 16 -1 (4775 3900)(5025 3900);
WIRE 16 -1 (5025 3950)(5025 3900);
WIRE 16 -1 (4775 3850)(5025 3850);
WIRE 16 -1 (5025 3900)(5025 3850);
WIRE 16 -1 (4775 3800)(5025 3800);
WIRE 16 -1 (5025 3850)(5025 3800);
WIRE 16 -1 (4775 3750)(5025 3750);
WIRE 16 -1 (5025 3800)(5025 3750);
WIRE 16 -1 (4775 3700)(5025 3700);
WIRE 16 -1 (5025 3750)(5025 3700);
WIRE 16 -1 (4775 3650)(5025 3650);
WIRE 16 -1 (5025 3650)(5025 3700);
WIRE 16 -1 (4775 3600)(5025 3600);
WIRE 16 -1 (5025 3650)(5025 3600);
WIRE 16 -1 (5025 3550)(4775 3550);
WIRE 16 -1 (5025 3600)(5025 3550);
WIRE 16 -1 (5025 3500)(4775 3500);
WIRE 16 -1 (5025 3550)(5025 3500);
WIRE 16 -1 (4775 3450)(5025 3450);
WIRE 16 -1 (5025 3500)(5025 3450);
WIRE 16 -1 (4775 3400)(5025 3400);
WIRE 16 -1 (5025 3450)(5025 3400);
WIRE 16 -1 (4775 3350)(5025 3350);
WIRE 16 -1 (5025 3400)(5025 3350);
WIRE 16 -1 (4775 3300)(5025 3300);
WIRE 16 -1 (5025 3350)(5025 3300);
WIRE 16 -1 (4775 3250)(5025 3250);
WIRE 16 -1 (5025 3300)(5025 3250);
WIRE 16 -1 (4775 3200)(5025 3200);
WIRE 16 -1 (5025 3250)(5025 3200);
WIRE 16 -1 (4775 3150)(5025 3150);
WIRE 16 -1 (5025 3150)(5025 3200);
WIRE 16 -1 (4775 3100)(5025 3100);
WIRE 16 -1 (5025 3150)(5025 3100);
WIRE 16 -1 (5025 3050)(4775 3050);
WIRE 16 -1 (5025 3100)(5025 3050);
WIRE 16 -1 (5025 3000)(4775 3000);
WIRE 16 -1 (5025 3050)(5025 3000);
WIRE 16 -1 (4775 2950)(5025 2950);
WIRE 16 -1 (5025 3000)(5025 2950);
WIRE 16 -1 (4775 2900)(5025 2900);
WIRE 16 -1 (5025 2950)(5025 2900);
WIRE 16 -1 (4775 2850)(5025 2850);
WIRE 16 -1 (5025 2900)(5025 2850);
WIRE 16 -1 (4775 2800)(5025 2800);
WIRE 16 -1 (5025 2850)(5025 2800);
WIRE 16 -1 (4775 2750)(5025 2750);
WIRE 16 -1 (5025 2800)(5025 2750);
WIRE 16 -1 (4775 2700)(5025 2700);
WIRE 16 -1 (5025 2750)(5025 2700);
WIRE 16 -1 (4775 2650)(5025 2650);
WIRE 16 -1 (5025 2650)(5025 2700);
WIRE 16 -1 (4775 2600)(5025 2600);
WIRE 16 -1 (5025 2650)(5025 2600);
WIRE 16 -1 (5025 2550)(4775 2550);
WIRE 16 -1 (5025 2600)(5025 2550);
WIRE 16 -1 (5025 2500)(4775 2500);
WIRE 16 -1 (5025 2550)(5025 2500);
WIRE 16 -1 (4775 2450)(5025 2450);
WIRE 16 -1 (5025 2500)(5025 2450);
WIRE 16 -1 (4775 2400)(5025 2400);
WIRE 16 -1 (5025 2450)(5025 2400);
WIRE 16 -1 (4775 2350)(5025 2350);
WIRE 16 -1 (5025 2400)(5025 2350);
WIRE 16 -1 (4775 2300)(5025 2300);
WIRE 16 -1 (5025 2350)(5025 2300);
WIRE 16 -1 (4775 2250)(5025 2250);
WIRE 16 -1 (5025 2300)(5025 2250);
WIRE 16 -1 (4775 2200)(5025 2200);
WIRE 16 -1 (5025 2250)(5025 2200);
WIRE 16 -1 (4775 2150)(5025 2150);
WIRE 16 -1 (5025 2150)(5025 2200);
WIRE 16 -1 (4775 2100)(5025 2100);
WIRE 16 -1 (5025 2150)(5025 2100);
WIRE 16 -1 (5025 2050)(4775 2050);
WIRE 16 -1 (5025 2100)(5025 2050);
WIRE 16 -1 (5025 2000)(4775 2000);
WIRE 16 -1 (5025 2050)(5025 2000);
WIRE 16 -1 (5025 1950)(4775 1950);
WIRE 16 -1 (5025 2000)(5025 1950);
WIRE 16 -1 (5025 1900)(4775 1900);
WIRE 16 -1 (5025 1950)(5025 1900);
WIRE 16 -1 (4775 1850)(5025 1850);
WIRE 16 -1 (5025 1850)(5025 1900);
WIRE 16 -1 (5025 1800)(4775 1800);
WIRE 16 -1 (5025 1800)(5025 1850);
WIRE 16 -1 (5025 1750)(4775 1750);
WIRE 16 -1 (5025 1800)(5025 1750);
WIRE 16 -1 (5025 1700)(4775 1700);
WIRE 16 -1 (5025 1750)(5025 1700);
WIRE 16 -1 (4775 1650)(5025 1650);
WIRE 16 -1 (5025 1700)(5025 1650);
WIRE 16 -1 (4775 1600)(5025 1600);
WIRE 16 -1 (5025 1650)(5025 1600);
WIRE 16 -1 (4775 1550)(5025 1550);
WIRE 16 -1 (5025 1600)(5025 1550);
WIRE 16 -1 (4775 1500)(5025 1500);
WIRE 16 -1 (5025 1550)(5025 1500);
WIRE 16 -1 (4775 1450)(5025 1450);
WIRE 16 -1 (5025 1500)(5025 1450);
WIRE 16 -1 (4775 1400)(5025 1400);
WIRE 16 -1 (5025 1450)(5025 1400);
WIRE 16 -1 (4775 1350)(5025 1350);
WIRE 16 -1 (5025 1400)(5025 1350);
WIRE 16 -1 (4775 1300)(5025 1300);
WIRE 16 -1 (5025 1300)(5025 1350);
WIRE 16 -1 (4775 1250)(5025 1250);
WIRE 16 -1 (5025 1300)(5025 1250);
WIRE 16 -1 (4775 1150)(5025 1150);
WIRE 16 -1 (5025 1250)(5025 1150);
WIRE 16 -1 (5025 1150)(5025 1100);
WIRE 16 -1 (4775 1100)(5025 1100);
WIRE 16 -1 (-1325 1250)(-1150 1250);
WIRE 16 3135 (275 1025)(275 -275);
WIRE 16 3135 (2875 1025)(275 1025);
WIRE 16 3135 (275 -275)(2875 -275);
WIRE 16 3135 (2875 -275)(2875 1025);
WIRE 16 -1 (-2525 1200)(-3625 1200);
FORCEPROP 2 LAST SIG_NAME TP_CHF_CPU0_DIMM1_FRU_1
J 0
(-3537 1209);
DISPLAY 0.680851 (-3537 1209);
PAINT WHITE (-3537 1209);
WIRE 16 -1 (-2525 1250)(-3625 1250);
FORCEPROP 2 LAST SIG_NAME TP_CHF_CPU0_DIMM1_FRU_2
J 0
(-3537 1259);
DISPLAY 0.680851 (-3537 1259);
PAINT WHITE (-3537 1259);
WIRE 16 -1 (-2525 1350)(-3625 1350);
FORCEPROP 2 LAST SIG_NAME TP_CHF_CPU0_DIMM1_FRU_4
J 0
(-3537 1359);
DISPLAY 0.680851 (-3537 1359);
PAINT WHITE (-3537 1359);
WIRE 16 -1 (-2525 1400)(-3625 1400);
FORCEPROP 2 LAST SIG_NAME TP_CHF_CPU0_DIMM1_FRU_5
J 0
(-3537 1409);
DISPLAY 0.680851 (-3537 1409);
PAINT WHITE (-3537 1409);
WIRE 16 -1 (-2525 3550)(-3625 3550);
FORCEPROP 2 LAST SIG_NAME M_F_CPU0_SB_PAR
J 0
(-3537 3559);
DISPLAY 0.680851 (-3537 3559);
PAINT WHITE (-3537 3559);
WIRE 16 -1 (-2525 3600)(-3625 3600);
FORCEPROP 2 LAST SIG_NAME M_F_CPU0_SA_PAR
J 0
(-3537 3609);
DISPLAY 0.680851 (-3537 3609);
PAINT WHITE (-3537 3609);
WIRE 16 -1 (-2525 1000)(-3625 1000);
FORCEPROP 2 LAST SIG_NAME M_F_CPU0_SA_RSP<0>
J 0
(-3537 1009);
DISPLAY 0.680851 (-3537 1009);
PAINT WHITE (-3537 1009);
WIRE 16 -1 (-1325 1200)(-1150 1200);
WIRE 16 -1 (-1325 1300)(-1150 1300);
WIRE 16 -1 (-1325 1350)(-1150 1350);
WIRE 16 -1 (-1325 1400)(-1150 1400);
WIRE 16 -1 (-1325 1450)(-1150 1450);
WIRE 16 -1 (-1325 1550)(-1150 1550);
WIRE 16 -1 (-1325 1600)(-1150 1600);
WIRE 16 -1 (-1325 1650)(-1150 1650);
WIRE 16 -1 (-1325 1700)(-1150 1700);
WIRE 16 -1 (-1325 1750)(-1150 1750);
WIRE 16 -1 (-1325 1800)(-1150 1800);
WIRE 16 -1 (-1325 1850)(-1150 1850);
WIRE 16 -1 (-1325 1900)(-1150 1900);
WIRE 16 -1 (-1325 1950)(-1150 1950);
WIRE 16 -1 (-1325 2000)(-1150 2000);
WIRE 16 -1 (-1325 2050)(-1150 2050);
WIRE 16 -1 (-1325 2100)(-1150 2100);
WIRE 16 -1 (-1325 2200)(-1150 2200);
WIRE 16 -1 (-1325 2250)(-1150 2250);
WIRE 16 -1 (-1325 2300)(-1150 2300);
WIRE 16 -1 (-1325 2350)(-1150 2350);
WIRE 16 -1 (-1325 2400)(-1150 2400);
WIRE 16 -1 (-1325 2450)(-1150 2450);
WIRE 16 -1 (-1325 2500)(-1150 2500);
WIRE 16 -1 (-1325 2550)(-1150 2550);
WIRE 16 -1 (-1325 2600)(-1150 2600);
WIRE 16 -1 (-1325 2650)(-1150 2650);
WIRE 16 -1 (-1325 2700)(-1150 2700);
WIRE 16 -1 (-1325 2750)(-1150 2750);
WIRE 16 -1 (-1325 2850)(-1150 2850);
WIRE 16 -1 (-1325 2900)(-1150 2900);
WIRE 16 -1 (-1325 2950)(-1150 2950);
WIRE 16 -1 (-1325 3000)(-1150 3000);
WIRE 16 -1 (-1325 3050)(-1150 3050);
WIRE 16 -1 (-1325 3100)(-1150 3100);
WIRE 16 -1 (-1325 3150)(-1150 3150);
WIRE 16 -1 (-1325 3200)(-1150 3200);
WIRE 16 -1 (-1325 3250)(-1150 3250);
WIRE 16 -1 (-1325 3350)(-1150 3350);
WIRE 16 -1 (-1325 3400)(-1150 3400);
WIRE 16 -1 (-1325 3500)(-1150 3500);
WIRE 16 -1 (-1325 3550)(-1150 3550);
WIRE 16 -1 (-1325 3600)(-1150 3600);
WIRE 16 -1 (-1325 3650)(-1150 3650);
WIRE 16 -1 (-1325 3700)(-1150 3700);
WIRE 16 -1 (-1325 3750)(-1150 3750);
WIRE 16 -1 (-1325 3800)(-1150 3800);
WIRE 16 -1 (-1325 3850)(-1150 3850);
WIRE 16 -1 (-1325 3900)(-1150 3900);
WIRE 16 -1 (-1325 3950)(-1150 3950);
WIRE 16 -1 (-1325 4000)(-1150 4000);
WIRE 16 -1 (-1325 4050)(-1150 4050);
WIRE 16 -1 (-1325 4100)(-1150 4100);
WIRE 16 -1 (-1325 4150)(-1150 4150);
WIRE 16 -1 (-1325 4200)(-1150 4200);
WIRE 16 -1 (-1325 4250)(-1150 4250);
WIRE 16 -1 (-1325 4300)(-1150 4300);
WIRE 16 -1 (-2525 3300)(-3625 3300);
FORCEPROP 2 LAST SIG_NAME M_F_CPU0_SB_CS_N<1>
J 0
(-3537 3309);
DISPLAY 0.680851 (-3537 3309);
PAINT WHITE (-3537 3309);
WIRE 16 -1 (-2525 3450)(-3625 3450);
FORCEPROP 2 LAST SIG_NAME M_F_CPU0_SA_CS_N<1>
J 0
(-3537 3459);
DISPLAY 0.680851 (-3537 3459);
PAINT WHITE (-3537 3459);
WIRE 16 -1 (-2525 3250)(-3625 3250);
FORCEPROP 2 LAST SIG_NAME M_F_CPU0_SB_CS_N<0>
J 0
(-3537 3259);
DISPLAY 0.680851 (-3537 3259);
PAINT WHITE (-3537 3259);
WIRE 16 -1 (-2525 3400)(-3625 3400);
FORCEPROP 2 LAST SIG_NAME M_F_CPU0_SA_CS_N<0>
J 0
(-3537 3409);
DISPLAY 0.680851 (-3537 3409);
PAINT WHITE (-3537 3409);
WIRE 16 -1 (-2525 3150)(-3625 3150);
FORCEPROP 2 LAST SIG_NAME M_F_CPU0_CLK_DP<0>
J 0
(-3537 3159);
DISPLAY 0.680851 (-3537 3159);
PAINT WHITE (-3537 3159);
WIRE 16 -1 (-2525 3100)(-3625 3100);
FORCEPROP 2 LAST SIG_NAME M_F_CPU0_CLK_DN<0>
J 0
(-3537 3109);
DISPLAY 0.680851 (-3537 3109);
PAINT WHITE (-3537 3109);
WIRE 16 -1 (-2700 2200)(-2525 2200);
WIRE 16 -1 (-2700 2250)(-2525 2250);
WIRE 16 -1 (-2700 2300)(-2525 2300);
WIRE 16 -1 (-2700 2350)(-2525 2350);
WIRE 16 -1 (-2700 2400)(-2525 2400);
WIRE 16 -1 (-2700 2450)(-2525 2450);
WIRE 16 -1 (-2700 2500)(-2525 2500);
WIRE 16 -1 (-2700 2650)(-2525 2650);
WIRE 16 -1 (-2700 2750)(-2525 2750);
WIRE 16 -1 (-2700 2800)(-2525 2800);
WIRE 16 -1 (-2700 2900)(-2525 2900);
WIRE 16 -1 (-2700 2950)(-2525 2950);
WIRE 16 -1 (-2700 4000)(-2525 4000);
WIRE 16 -1 (-2700 4400)(-2525 4400);
WIRE 16 -1 (-2700 3950)(-2525 3950);
WIRE 16 -1 (-2700 4350)(-2525 4350);
WIRE 16 -1 (-2700 3900)(-2525 3900);
WIRE 16 -1 (-2700 4300)(-2525 4300);
WIRE 16 -1 (-2700 3850)(-2525 3850);
WIRE 16 -1 (-2700 4250)(-2525 4250);
WIRE 16 -1 (-2700 3800)(-2525 3800);
WIRE 16 -1 (-2700 4200)(-2525 4200);
WIRE 16 -1 (-2700 3750)(-2525 3750);
WIRE 16 -1 (-2700 4150)(-2525 4150);
WIRE 16 -1 (-2700 3700)(-2525 3700);
WIRE 16 -1 (-2700 4100)(-2525 4100);
WIRE 16 -1 (-2700 2550)(-2525 2550);
WIRE 16 -1 (-2700 2700)(-2525 2700);
WIRE 16 -1 (-2700 3000)(-2525 3000);
WIRE 16 -1 (-2525 450)(-3625 450);
FORCEPROP 2 LAST SIG_NAME PD_CHF_CPU0_DIMM1_SAA
J 0
(-3537 459);
DISPLAY 0.680851 (-3537 459);
PAINT WHITE (-3537 459);
WIRE 16 -1 (-2525 350)(-2525 450);
WIRE 16 -1 (1625 750)(1625 625);
WIRE 16 -1 (2250 750)(1625 750);
WIRE 16 -1 (2250 625)(2250 750);
WIRE 16 -1 (1625 275)(1625 425);
WIRE 16 -1 (2250 275)(1625 275);
WIRE 16 -1 (2250 275)(2250 425);
DOT 1 (3325 3900);
DOT 1 (3325 3950);
DOT 1 (3325 1200);
DOT 1 (5025 1550);
DOT 1 (3325 1150);
DOT 1 (5025 4350);
DOT 1 (5025 4300);
DOT 1 (5025 4250);
DOT 1 (5025 4200);
DOT 1 (5025 4150);
DOT 1 (5025 4100);
DOT 1 (5025 4050);
DOT 1 (5025 4000);
DOT 1 (5025 3950);
DOT 1 (5025 3900);
DOT 1 (5025 3850);
DOT 1 (5025 3800);
DOT 1 (5025 3750);
DOT 1 (5025 3700);
DOT 1 (5025 3650);
DOT 1 (5025 3600);
DOT 1 (5025 3550);
DOT 1 (5025 3500);
DOT 1 (5025 3450);
DOT 1 (5025 3400);
DOT 1 (5025 3350);
DOT 1 (5025 3300);
DOT 1 (5025 3250);
DOT 1 (5025 3200);
DOT 1 (5025 3150);
DOT 1 (5025 3100);
DOT 1 (5025 3050);
DOT 1 (5025 3000);
DOT 1 (5025 2950);
DOT 1 (5025 2900);
DOT 1 (5025 2850);
DOT 1 (5025 2800);
DOT 1 (5025 2750);
DOT 1 (5025 2700);
DOT 1 (5025 2600);
DOT 1 (5025 2650);
DOT 1 (5025 2550);
DOT 1 (5025 2500);
DOT 1 (5025 2450);
DOT 1 (5025 2400);
DOT 1 (5025 2350);
DOT 1 (5025 2300);
DOT 1 (5025 2250);
DOT 1 (5025 2200);
DOT 1 (5025 2150);
DOT 1 (5025 2100);
DOT 1 (5025 2050);
DOT 1 (5025 2000);
DOT 1 (5025 1950);
DOT 1 (5025 1900);
DOT 1 (5025 1850);
DOT 1 (5025 1800);
DOT 1 (5025 1750);
DOT 1 (5025 1700);
DOT 1 (5025 1650);
DOT 1 (5025 1600);
DOT 1 (5025 1500);
DOT 1 (5025 1450);
DOT 1 (5025 1400);
DOT 1 (5025 1350);
DOT 1 (5025 1300);
DOT 1 (5025 1250);
DOT 1 (3325 4400);
DOT 1 (3325 4350);
DOT 1 (3325 4150);
DOT 1 (3325 4200);
DOT 1 (3325 4100);
DOT 1 (3325 4050);
DOT 1 (3325 4000);
DOT 1 (3325 3850);
DOT 1 (3325 3750);
DOT 1 (3325 3800);
DOT 1 (3325 3650);
DOT 1 (3325 3600);
DOT 1 (3325 3700);
DOT 1 (3325 3500);
DOT 1 (3325 3550);
DOT 1 (3325 3450);
DOT 1 (3325 3400);
DOT 1 (3325 3350);
DOT 1 (3325 3250);
DOT 1 (3325 3300);
DOT 1 (3325 3200);
DOT 1 (3325 3150);
DOT 1 (3325 3100);
DOT 1 (3325 3050);
DOT 1 (3325 3000);
DOT 1 (3325 2950);
DOT 1 (3325 2900);
DOT 1 (3325 2850);
DOT 1 (3325 2800);
DOT 1 (3325 2750);
DOT 1 (3325 2700);
DOT 1 (3325 2600);
DOT 1 (3325 2650);
DOT 1 (3325 2450);
DOT 1 (3325 2500);
DOT 1 (3325 2550);
DOT 1 (3325 2400);
DOT 1 (3325 2350);
DOT 1 (3325 2300);
DOT 1 (3325 2200);
DOT 1 (3325 2250);
DOT 1 (3325 2100);
DOT 1 (3325 2150);
DOT 1 (3325 2050);
DOT 1 (3325 1950);
DOT 1 (3325 1900);
DOT 1 (3325 1850);
DOT 1 (3325 1800);
DOT 1 (3325 1700);
DOT 1 (3325 1750);
DOT 1 (3325 1650);
DOT 1 (3325 1600);
DOT 1 (3325 1550);
DOT 1 (3325 1450);
DOT 1 (3325 1500);
DOT 1 (3325 1350);
DOT 1 (3325 1300);
DOT 1 (3325 1250);
DOT 1 (2250 275);
DOT 1 (1625 750);
DOT 1 (3325 1400);
DOT 1 (5025 1150);
DOT 1 (5025 1100);
DOT 1 (5025 1050);
DOT 1 (3325 2000);
FORCENOTE
20210728 MODIFY FOR GT
(-3975 5075) 0;
DISPLAY LEFT (-3975 5075);
DISPLAY 2.510638 (-3975 5075);
PAINT PINK (-3975 5075);
QUIT
